G04*
G04 #@! TF.GenerationSoftware,Altium Limited,Altium Designer,23.0.1 (38)*
G04*
G04 Layer_Physical_Order=6*
G04 Layer_Color=16711680*
%FSLAX25Y25*%
%MOIN*%
G70*
G04*
G04 #@! TF.SameCoordinates,C48E81DB-6E20-4E2D-80E6-7C5AFAA1A21F*
G04*
G04*
G04 #@! TF.FilePolarity,Positive*
G04*
G01*
G75*
%ADD12C,0.02000*%
%ADD14C,0.01000*%
%ADD19C,0.00500*%
%ADD24C,0.00800*%
%ADD82R,0.02520X0.02677*%
%ADD128R,0.02800X0.16500*%
%ADD129R,0.02800X0.12600*%
G04:AMPARAMS|DCode=155|XSize=43.31mil|YSize=139.76mil|CornerRadius=21.65mil|HoleSize=0mil|Usage=FLASHONLY|Rotation=90.000|XOffset=0mil|YOffset=0mil|HoleType=Round|Shape=RoundedRectangle|*
%AMROUNDEDRECTD155*
21,1,0.04331,0.09646,0,0,90.0*
21,1,0.00000,0.13976,0,0,90.0*
1,1,0.04331,0.04823,0.00000*
1,1,0.04331,0.04823,0.00000*
1,1,0.04331,-0.04823,0.00000*
1,1,0.04331,-0.04823,0.00000*
%
%ADD155ROUNDEDRECTD155*%
G04:AMPARAMS|DCode=212|XSize=43.31mil|YSize=70.87mil|CornerRadius=21.65mil|HoleSize=0mil|Usage=FLASHONLY|Rotation=90.000|XOffset=0mil|YOffset=0mil|HoleType=Round|Shape=RoundedRectangle|*
%AMROUNDEDRECTD212*
21,1,0.04331,0.02756,0,0,90.0*
21,1,0.00000,0.07087,0,0,90.0*
1,1,0.04331,0.01378,0.00000*
1,1,0.04331,0.01378,0.00000*
1,1,0.04331,-0.01378,0.00000*
1,1,0.04331,-0.01378,0.00000*
%
%ADD212ROUNDEDRECTD212*%
G04:AMPARAMS|DCode=213|XSize=47.24mil|YSize=62.99mil|CornerRadius=23.62mil|HoleSize=0mil|Usage=FLASHONLY|Rotation=90.000|XOffset=0mil|YOffset=0mil|HoleType=Round|Shape=RoundedRectangle|*
%AMROUNDEDRECTD213*
21,1,0.04724,0.01575,0,0,90.0*
21,1,0.00000,0.06299,0,0,90.0*
1,1,0.04724,0.00787,0.00000*
1,1,0.04724,0.00787,0.00000*
1,1,0.04724,-0.00787,0.00000*
1,1,0.04724,-0.00787,0.00000*
%
%ADD213ROUNDEDRECTD213*%
%ADD214C,0.11800*%
%ADD215R,0.10827X0.10827*%
%ADD216C,0.10827*%
%ADD239R,0.06102X0.06102*%
%ADD240C,0.06102*%
%ADD241C,0.10000*%
%ADD242C,0.02166*%
%ADD243C,0.24000*%
%ADD244C,0.06598*%
%ADD245C,0.08661*%
%ADD246R,0.07874X0.07874*%
%ADD247R,0.05906X0.05906*%
%ADD248C,0.05906*%
%ADD249C,0.25000*%
%ADD250C,0.01600*%
%ADD251C,0.05000*%
%ADD252C,0.20000*%
%ADD253C,0.01968*%
%ADD254C,0.00500*%
%ADD255C,0.08000*%
%ADD256R,0.07382X0.06791*%
G36*
X672047Y-8218D02*
X671818Y-8328D01*
X671547Y-8372D01*
X671098Y-7923D01*
X670437Y-7649D01*
X669721D01*
X669059Y-7923D01*
X668553Y-8429D01*
X668279Y-9091D01*
Y-9807D01*
X668553Y-10468D01*
X669059Y-10975D01*
X669721Y-11249D01*
X670437D01*
X671098Y-10975D01*
X671547Y-10526D01*
X671818Y-10570D01*
X672047Y-10679D01*
Y-11024D01*
X674016D01*
Y-27455D01*
X673600Y-27733D01*
X673586Y-27728D01*
X672870D01*
X672209Y-28002D01*
X671702Y-28508D01*
X671428Y-29169D01*
Y-29886D01*
X671702Y-30547D01*
X672209Y-31054D01*
X672870Y-31328D01*
X673586D01*
X673600Y-31322D01*
X674016Y-31600D01*
Y-41365D01*
X673953Y-41416D01*
X673454Y-41180D01*
Y-40980D01*
X673179Y-40319D01*
X672673Y-39813D01*
X672012Y-39539D01*
X671295D01*
X670634Y-39813D01*
X670128Y-40319D01*
X669853Y-40980D01*
Y-41697D01*
X670128Y-42358D01*
X670634Y-42865D01*
X671295Y-43139D01*
X672012D01*
X672673Y-42865D01*
X673179Y-42358D01*
X673283Y-42109D01*
X673358Y-42009D01*
X673791Y-42162D01*
X673791Y-42329D01*
Y-42878D01*
X674016Y-43421D01*
Y-61024D01*
X672555D01*
X672012Y-60798D01*
X671295D01*
X670752Y-61024D01*
X666142D01*
Y-83071D01*
X640551D01*
Y-94205D01*
X640545Y-94242D01*
Y-95973D01*
X640551Y-96011D01*
Y-107874D01*
X660925D01*
X661013Y-108085D01*
X661519Y-108592D01*
X662181Y-108866D01*
X662897D01*
X663559Y-108592D01*
X664065Y-108085D01*
X664067Y-108080D01*
X664567Y-108180D01*
Y-145276D01*
X679134D01*
Y-158614D01*
X678902Y-158710D01*
X678395Y-159217D01*
X678121Y-159878D01*
Y-160594D01*
X678395Y-161256D01*
X678902Y-161762D01*
X679134Y-161858D01*
Y-162598D01*
X683024D01*
X683120Y-162831D01*
X683626Y-163337D01*
X684288Y-163611D01*
X685004D01*
X685665Y-163337D01*
X686172Y-162831D01*
X686268Y-162598D01*
X687402D01*
Y-169685D01*
X688862D01*
X689406Y-169910D01*
X690122D01*
X690665Y-169685D01*
X691732D01*
Y-203937D01*
X670216D01*
Y-165530D01*
X670304Y-165319D01*
Y-164603D01*
X670216Y-164391D01*
Y-162020D01*
X653543D01*
Y-120079D01*
X633071D01*
Y-85074D01*
X633340Y-84804D01*
X633614Y-84142D01*
Y-83426D01*
X633340Y-82765D01*
X633071Y-82495D01*
Y-69291D01*
X645276D01*
Y-45669D01*
X660236Y-31496D01*
Y-30200D01*
X660265Y-30131D01*
Y-29415D01*
X660236Y-29347D01*
Y-22326D01*
X660265Y-22257D01*
Y-21541D01*
X660236Y-21473D01*
Y-20866D01*
X659977D01*
X659484Y-20373D01*
X658823Y-20099D01*
X658107D01*
X657445Y-20373D01*
X657346Y-20472D01*
X652756D01*
Y-6299D01*
X672047D01*
Y-8218D01*
D02*
G37*
G36*
X398031Y-105118D02*
X372835D01*
Y-133071D01*
X384646D01*
Y-147638D01*
X359055D01*
Y-94882D01*
X361417D01*
Y-72835D01*
X398031D01*
Y-105118D01*
D02*
G37*
G36*
X355906Y-146850D02*
X315748D01*
Y-164173D01*
X297862D01*
Y-163770D01*
X297542Y-161749D01*
X296910Y-159803D01*
X295981Y-157979D01*
X294778Y-156324D01*
X293331Y-154877D01*
X291676Y-153674D01*
X291339Y-153503D01*
Y-131102D01*
X321260D01*
Y-108661D01*
X355906D01*
Y-146850D01*
D02*
G37*
G36*
X435827Y-134992D02*
X435595Y-135088D01*
X435088Y-135595D01*
X434814Y-136256D01*
Y-136972D01*
X435088Y-137634D01*
X435595Y-138140D01*
X435827Y-138236D01*
Y-138976D01*
X468337D01*
X468501Y-139141D01*
X469163Y-139415D01*
X469879D01*
X470540Y-139141D01*
X470639Y-139042D01*
X474770D01*
X527863Y-192135D01*
X527724Y-192703D01*
X527215Y-192914D01*
X526629Y-193500D01*
X526312Y-194265D01*
Y-195094D01*
X526629Y-195860D01*
X527215Y-196446D01*
X527981Y-196763D01*
X528810D01*
X529575Y-196446D01*
X530161Y-195860D01*
X530372Y-195351D01*
X530940Y-195212D01*
X531496Y-195768D01*
Y-201792D01*
X531138D01*
X530477Y-202066D01*
X529970Y-202572D01*
X529696Y-203234D01*
Y-203950D01*
X529970Y-204612D01*
X530477Y-205118D01*
X531138Y-205392D01*
X531496D01*
Y-208661D01*
X488239D01*
X478740Y-199162D01*
Y-173599D01*
X478745Y-173586D01*
Y-172870D01*
X478740Y-172858D01*
Y-171653D01*
X477847D01*
X477303Y-171428D01*
X476587D01*
X476044Y-171653D01*
X473672D01*
X472269Y-170250D01*
X471806Y-169941D01*
X471260Y-169832D01*
X471260Y-169832D01*
X464374D01*
X464374Y-169832D01*
X463828Y-169941D01*
X463364Y-170250D01*
X463364Y-170250D01*
X461961Y-171653D01*
X388189D01*
Y-132677D01*
X385585D01*
X385367Y-132350D01*
X385036Y-132129D01*
X384646Y-132051D01*
X373854D01*
Y-109843D01*
X435827D01*
Y-134992D01*
D02*
G37*
G36*
X658661Y-241732D02*
Y-258661D01*
Y-285827D01*
X636614Y-307874D01*
Y-318898D01*
X563779D01*
X532677Y-287795D01*
Y-266142D01*
X538976Y-259842D01*
X548032D01*
X571260Y-236614D01*
X586109D01*
X586179Y-236643D01*
X586895D01*
X586966Y-236614D01*
X606876D01*
X607135Y-237240D01*
X607642Y-237746D01*
X608303Y-238020D01*
X609020D01*
X609681Y-237746D01*
X610187Y-237240D01*
X610447Y-236614D01*
X635778D01*
X635887Y-236844D01*
X635931Y-237114D01*
X635482Y-237563D01*
X635208Y-238225D01*
Y-238941D01*
X635482Y-239602D01*
X635988Y-240109D01*
X636650Y-240383D01*
X637366D01*
X638027Y-240109D01*
X638534Y-239602D01*
X638808Y-238941D01*
Y-238225D01*
X638534Y-237563D01*
X638085Y-237114D01*
X638129Y-236844D01*
X638238Y-236614D01*
X653543D01*
X658661Y-241732D01*
D02*
G37*
%LPC*%
G36*
X658823Y-35847D02*
X658107D01*
X657445Y-36121D01*
X656939Y-36628D01*
X656665Y-37289D01*
Y-38005D01*
X656939Y-38667D01*
X657445Y-39173D01*
X658107Y-39447D01*
X658823D01*
X659484Y-39173D01*
X659991Y-38667D01*
X660265Y-38005D01*
Y-37289D01*
X659991Y-36628D01*
X659484Y-36121D01*
X658823Y-35847D01*
D02*
G37*
G36*
X658472Y-54914D02*
X657756D01*
X657094Y-55188D01*
X656588Y-55695D01*
X656314Y-56356D01*
Y-57072D01*
X656588Y-57734D01*
X657094Y-58240D01*
X657756Y-58514D01*
X658472D01*
X659134Y-58240D01*
X659640Y-57734D01*
X659914Y-57072D01*
Y-56356D01*
X659640Y-55695D01*
X659134Y-55188D01*
X658472Y-54914D01*
D02*
G37*
G36*
X657803Y-61725D02*
X657087D01*
X656426Y-62000D01*
X655919Y-62506D01*
X655645Y-63168D01*
Y-63884D01*
X655919Y-64545D01*
X656426Y-65052D01*
X657087Y-65325D01*
X657803D01*
X658465Y-65052D01*
X658971Y-64545D01*
X659245Y-63884D01*
Y-63168D01*
X658971Y-62506D01*
X658465Y-62000D01*
X657803Y-61725D01*
D02*
G37*
G36*
X658411Y-69388D02*
X657695D01*
X657034Y-69662D01*
X656527Y-70169D01*
X656253Y-70830D01*
Y-71546D01*
X656527Y-72208D01*
X657034Y-72714D01*
X657695Y-72988D01*
X658411D01*
X659073Y-72714D01*
X659579Y-72208D01*
X659853Y-71546D01*
Y-70830D01*
X659579Y-70169D01*
X659073Y-69662D01*
X658411Y-69388D01*
D02*
G37*
G36*
X661077Y-73927D02*
X660361D01*
X659699Y-74200D01*
X659193Y-74707D01*
X658919Y-75368D01*
Y-76085D01*
X659193Y-76746D01*
X659699Y-77252D01*
X660361Y-77526D01*
X661077D01*
X661739Y-77252D01*
X662245Y-76746D01*
X662519Y-76085D01*
Y-75368D01*
X662245Y-74707D01*
X661739Y-74200D01*
X661077Y-73927D01*
D02*
G37*
G36*
X677523Y-170641D02*
X676807D01*
X676146Y-170915D01*
X675639Y-171421D01*
X675467Y-171836D01*
X674926D01*
X674754Y-171421D01*
X674248Y-170915D01*
X673586Y-170641D01*
X672870D01*
X672209Y-170915D01*
X671702Y-171421D01*
X671428Y-172083D01*
Y-172799D01*
X671702Y-173461D01*
X672209Y-173967D01*
X672870Y-174241D01*
X673586D01*
X674248Y-173967D01*
X674754Y-173461D01*
X674926Y-173046D01*
X675467D01*
X675639Y-173461D01*
X676146Y-173967D01*
X676807Y-174241D01*
X677523D01*
X678185Y-173967D01*
X678691Y-173461D01*
X678965Y-172799D01*
Y-172083D01*
X678691Y-171421D01*
X678185Y-170915D01*
X677523Y-170641D01*
D02*
G37*
G36*
X681854Y-177728D02*
X681138D01*
X680476Y-178002D01*
X679970Y-178508D01*
X679696Y-179169D01*
Y-179886D01*
X679970Y-180547D01*
X680476Y-181053D01*
X681138Y-181328D01*
X681854D01*
X682516Y-181053D01*
X683022Y-180547D01*
X683296Y-179886D01*
Y-179169D01*
X683022Y-178508D01*
X682516Y-178002D01*
X681854Y-177728D01*
D02*
G37*
G36*
X403077Y-110533D02*
X402360D01*
X401699Y-110808D01*
X401193Y-111314D01*
X400919Y-111976D01*
Y-112692D01*
X401193Y-113353D01*
X401699Y-113859D01*
X402360Y-114134D01*
X403077D01*
X403738Y-113859D01*
X404245Y-113353D01*
X404519Y-112692D01*
Y-111976D01*
X404245Y-111314D01*
X403738Y-110808D01*
X403077Y-110533D01*
D02*
G37*
G36*
X430850Y-134673D02*
X430134D01*
X429472Y-134947D01*
X428966Y-135453D01*
X428692Y-136115D01*
Y-136831D01*
X428966Y-137493D01*
X429472Y-137999D01*
X430134Y-138273D01*
X430850D01*
X431512Y-137999D01*
X432018Y-137493D01*
X432292Y-136831D01*
Y-136115D01*
X432018Y-135453D01*
X431512Y-134947D01*
X430850Y-134673D01*
D02*
G37*
G36*
X410258Y-134759D02*
X409542D01*
X408880Y-135033D01*
X408374Y-135540D01*
X408100Y-136201D01*
Y-136917D01*
X408374Y-137579D01*
X408880Y-138085D01*
X409542Y-138359D01*
X410258D01*
X410920Y-138085D01*
X411426Y-137579D01*
X411700Y-136917D01*
Y-136201D01*
X411426Y-135540D01*
X410920Y-135033D01*
X410258Y-134759D01*
D02*
G37*
G36*
X414925Y-135602D02*
X414209D01*
X413547Y-135876D01*
X413041Y-136382D01*
X412767Y-137043D01*
Y-137760D01*
X413041Y-138421D01*
X413547Y-138927D01*
X414209Y-139202D01*
X414925D01*
X415587Y-138927D01*
X416093Y-138421D01*
X416367Y-137760D01*
Y-137043D01*
X416093Y-136382D01*
X415587Y-135876D01*
X414925Y-135602D01*
D02*
G37*
G36*
X419256Y-142343D02*
X418540D01*
X417878Y-142617D01*
X417483Y-143012D01*
X417125Y-142654D01*
X416464Y-142380D01*
X415747D01*
X415086Y-142654D01*
X414579Y-143160D01*
X414305Y-143822D01*
Y-144538D01*
X414579Y-145199D01*
X415086Y-145705D01*
X415747Y-145980D01*
X416464D01*
X417125Y-145705D01*
X417520Y-145311D01*
X417878Y-145669D01*
X418540Y-145943D01*
X419256D01*
X419917Y-145669D01*
X420424Y-145163D01*
X420698Y-144501D01*
Y-143785D01*
X420424Y-143124D01*
X419917Y-142617D01*
X419256Y-142343D01*
D02*
G37*
G36*
X469649Y-142048D02*
X468933D01*
X468272Y-142322D01*
X467765Y-142828D01*
X467491Y-143490D01*
Y-144206D01*
X467765Y-144868D01*
X468272Y-145374D01*
X468933Y-145648D01*
X469649D01*
X470311Y-145374D01*
X470817Y-144868D01*
X471091Y-144206D01*
Y-143490D01*
X470817Y-142828D01*
X470311Y-142322D01*
X469649Y-142048D01*
D02*
G37*
G36*
X398926Y-143283D02*
X398210D01*
X397549Y-143557D01*
X397042Y-144063D01*
X396768Y-144725D01*
Y-145441D01*
X397042Y-146103D01*
X397549Y-146609D01*
X398210Y-146883D01*
X398926D01*
X399588Y-146609D01*
X400094Y-146103D01*
X400368Y-145441D01*
Y-144725D01*
X400094Y-144063D01*
X399588Y-143557D01*
X398926Y-143283D01*
D02*
G37*
G36*
X461677Y-141950D02*
X460961D01*
X460299Y-142224D01*
X459793Y-142730D01*
X459519Y-143392D01*
Y-144108D01*
X459793Y-144769D01*
X460299Y-145276D01*
X460961Y-145550D01*
X461677D01*
X462296Y-145293D01*
X462434Y-145366D01*
X462703Y-145619D01*
X462528Y-146039D01*
Y-146755D01*
X462803Y-147417D01*
X463309Y-147923D01*
X463970Y-148197D01*
X464686D01*
X465348Y-147923D01*
X465854Y-147417D01*
X466128Y-146755D01*
Y-146039D01*
X465854Y-145377D01*
X465348Y-144871D01*
X464686Y-144597D01*
X463970D01*
X463351Y-144853D01*
X463213Y-144781D01*
X462945Y-144528D01*
X463119Y-144108D01*
Y-143392D01*
X462845Y-142730D01*
X462338Y-142224D01*
X461677Y-141950D01*
D02*
G37*
G36*
X400653Y-156024D02*
X399937D01*
X399276Y-156298D01*
X398769Y-156805D01*
X398495Y-157466D01*
Y-158182D01*
X398769Y-158844D01*
X399276Y-159350D01*
X399937Y-159624D01*
X400653D01*
X401315Y-159350D01*
X401821Y-158844D01*
X402095Y-158182D01*
Y-157466D01*
X401821Y-156805D01*
X401315Y-156298D01*
X400653Y-156024D01*
D02*
G37*
G36*
X459677Y-156122D02*
X458961D01*
X458299Y-156396D01*
X457793Y-156903D01*
X457519Y-157564D01*
Y-158280D01*
X457793Y-158942D01*
X458299Y-159448D01*
X458961Y-159722D01*
X459677D01*
X460338Y-159448D01*
X460845Y-158942D01*
X461119Y-158280D01*
Y-157564D01*
X460845Y-156903D01*
X460338Y-156396D01*
X459677Y-156122D01*
D02*
G37*
G36*
X450161Y-156123D02*
X449445D01*
X448783Y-156397D01*
X448277Y-156903D01*
X448003Y-157565D01*
Y-158281D01*
X448277Y-158942D01*
X448783Y-159449D01*
X449445Y-159723D01*
X450161D01*
X450823Y-159449D01*
X451329Y-158942D01*
X451603Y-158281D01*
Y-157565D01*
X451329Y-156903D01*
X450823Y-156397D01*
X450161Y-156123D01*
D02*
G37*
G36*
X440319D02*
X439603D01*
X438941Y-156397D01*
X438435Y-156903D01*
X438161Y-157565D01*
Y-158281D01*
X438435Y-158942D01*
X438941Y-159449D01*
X439603Y-159723D01*
X440319D01*
X440980Y-159449D01*
X441487Y-158942D01*
X441761Y-158281D01*
Y-157565D01*
X441487Y-156903D01*
X440980Y-156397D01*
X440319Y-156123D01*
D02*
G37*
G36*
X430508D02*
X429792D01*
X429130Y-156397D01*
X428624Y-156903D01*
X428350Y-157565D01*
Y-158281D01*
X428624Y-158942D01*
X429130Y-159449D01*
X429792Y-159723D01*
X430508D01*
X431169Y-159449D01*
X431676Y-158942D01*
X431950Y-158281D01*
Y-157565D01*
X431676Y-156903D01*
X431169Y-156397D01*
X430508Y-156123D01*
D02*
G37*
G36*
X421027D02*
X420311D01*
X419650Y-156397D01*
X419143Y-156903D01*
X418869Y-157565D01*
Y-158281D01*
X419143Y-158942D01*
X419650Y-159449D01*
X420311Y-159723D01*
X421027D01*
X421689Y-159449D01*
X422195Y-158942D01*
X422469Y-158281D01*
Y-157565D01*
X422195Y-156903D01*
X421689Y-156397D01*
X421027Y-156123D01*
D02*
G37*
G36*
X406886Y-155967D02*
X406170D01*
X405508Y-156241D01*
X405002Y-156747D01*
X404728Y-157409D01*
Y-158125D01*
X405002Y-158786D01*
X405508Y-159293D01*
X405932Y-159468D01*
X405680Y-160075D01*
Y-160791D01*
X405954Y-161453D01*
X406411Y-161909D01*
X406004Y-162317D01*
X405547Y-161860D01*
X404886Y-161586D01*
X404170D01*
X403508Y-161860D01*
X403502Y-161865D01*
X402913Y-161748D01*
X402806Y-161490D01*
X402299Y-160983D01*
X401638Y-160709D01*
X400921D01*
X400260Y-160983D01*
X399754Y-161490D01*
X399480Y-162151D01*
Y-162867D01*
X399754Y-163529D01*
X400260Y-164035D01*
X400921Y-164309D01*
X401638D01*
X402299Y-164035D01*
X402305Y-164030D01*
X402894Y-164147D01*
X403002Y-164405D01*
X403508Y-164912D01*
X404170Y-165186D01*
X404886D01*
X405547Y-164912D01*
X406004Y-164455D01*
X406461Y-164912D01*
X407122Y-165186D01*
X407838D01*
X408500Y-164912D01*
X409006Y-164405D01*
X409095Y-164192D01*
X409685Y-164074D01*
X409894Y-164284D01*
X410555Y-164558D01*
X411271D01*
X411933Y-164284D01*
X412439Y-163777D01*
X412713Y-163116D01*
Y-162399D01*
X412439Y-161738D01*
X411933Y-161232D01*
X411271Y-160958D01*
X410555D01*
X409894Y-161232D01*
X409389Y-161737D01*
X409006Y-161453D01*
X409280Y-160791D01*
Y-160075D01*
X409170Y-159809D01*
X409370Y-159596D01*
X409573Y-159476D01*
X410170Y-159723D01*
X410886D01*
X411547Y-159449D01*
X412053Y-158942D01*
X412328Y-158281D01*
Y-157565D01*
X412053Y-156903D01*
X411547Y-156397D01*
X410886Y-156123D01*
X410170D01*
X409508Y-156397D01*
X409002Y-156903D01*
X408810Y-157366D01*
X408624Y-157383D01*
X408289Y-157316D01*
X408053Y-156747D01*
X407547Y-156241D01*
X406886Y-155967D01*
D02*
G37*
G36*
X470699Y-158394D02*
X469870D01*
X469105Y-158711D01*
X468519Y-159297D01*
X468202Y-160062D01*
Y-160891D01*
X468519Y-161656D01*
X469105Y-162242D01*
X469870Y-162560D01*
X470699D01*
X471464Y-162242D01*
X472050Y-161656D01*
X472368Y-160891D01*
Y-160062D01*
X472050Y-159297D01*
X471464Y-158711D01*
X470699Y-158394D01*
D02*
G37*
G36*
X391959D02*
X391130D01*
X390365Y-158711D01*
X389779Y-159297D01*
X389461Y-160062D01*
Y-160891D01*
X389779Y-161656D01*
X390365Y-162242D01*
X391130Y-162560D01*
X391959D01*
X392724Y-162242D01*
X393310Y-161656D01*
X393628Y-160891D01*
Y-160062D01*
X393310Y-159297D01*
X392724Y-158711D01*
X391959Y-158394D01*
D02*
G37*
G36*
X430508Y-160453D02*
X429792D01*
X429130Y-160728D01*
X428624Y-161234D01*
X428350Y-161896D01*
Y-162612D01*
X428624Y-163273D01*
X429130Y-163779D01*
X429792Y-164053D01*
X430508D01*
X431169Y-163779D01*
X431676Y-163273D01*
X431950Y-162612D01*
Y-161896D01*
X431676Y-161234D01*
X431169Y-160728D01*
X430508Y-160453D01*
D02*
G37*
G36*
X459677Y-160710D02*
X458961D01*
X458299Y-160985D01*
X457793Y-161491D01*
X457519Y-162152D01*
Y-162868D01*
X457793Y-163530D01*
X458299Y-164036D01*
X458961Y-164310D01*
X459677D01*
X460338Y-164036D01*
X460845Y-163530D01*
X461119Y-162868D01*
Y-162152D01*
X460845Y-161491D01*
X460338Y-160985D01*
X459677Y-160710D01*
D02*
G37*
G36*
X449866Y-160749D02*
X449150D01*
X448488Y-161023D01*
X447982Y-161529D01*
X447708Y-162191D01*
Y-162907D01*
X447982Y-163568D01*
X448488Y-164075D01*
X449150Y-164349D01*
X449866D01*
X450527Y-164075D01*
X451034Y-163568D01*
X451308Y-162907D01*
Y-162191D01*
X451034Y-161529D01*
X450527Y-161023D01*
X449866Y-160749D01*
D02*
G37*
G36*
X440055D02*
X439339D01*
X438677Y-161023D01*
X438171Y-161529D01*
X437897Y-162191D01*
Y-162907D01*
X438171Y-163568D01*
X438677Y-164075D01*
X439339Y-164349D01*
X440055D01*
X440717Y-164075D01*
X441223Y-163568D01*
X441497Y-162907D01*
Y-162191D01*
X441223Y-161529D01*
X440717Y-161023D01*
X440055Y-160749D01*
D02*
G37*
G36*
X420437D02*
X419721D01*
X419059Y-161023D01*
X418553Y-161529D01*
X418279Y-162191D01*
Y-162907D01*
X418553Y-163568D01*
X419059Y-164075D01*
X419721Y-164349D01*
X420437D01*
X421098Y-164075D01*
X421605Y-163568D01*
X421879Y-162907D01*
Y-162191D01*
X421605Y-161529D01*
X421098Y-161023D01*
X420437Y-160749D01*
D02*
G37*
G36*
X499469Y-177728D02*
X498753D01*
X498091Y-178002D01*
X497585Y-178509D01*
X497311Y-179170D01*
Y-179886D01*
X497585Y-180548D01*
X498091Y-181054D01*
X498753Y-181328D01*
X499469D01*
X500130Y-181054D01*
X500637Y-180548D01*
X500911Y-179886D01*
Y-179170D01*
X500637Y-178509D01*
X500130Y-178002D01*
X499469Y-177728D01*
D02*
G37*
G36*
X499177Y-182058D02*
X498461D01*
X497799Y-182332D01*
X497293Y-182839D01*
X497019Y-183500D01*
Y-184216D01*
X497293Y-184878D01*
X497799Y-185384D01*
X498461Y-185658D01*
X499177D01*
X499838Y-185384D01*
X500345Y-184878D01*
X500619Y-184216D01*
Y-183500D01*
X500345Y-182839D01*
X499838Y-182332D01*
X499177Y-182058D01*
D02*
G37*
G36*
X499051Y-186551D02*
X498335D01*
X497673Y-186825D01*
X497167Y-187331D01*
X496893Y-187993D01*
Y-188709D01*
X497167Y-189370D01*
X497673Y-189877D01*
X498335Y-190151D01*
X499051D01*
X499713Y-189877D01*
X500219Y-189370D01*
X500493Y-188709D01*
Y-187993D01*
X500219Y-187331D01*
X499713Y-186825D01*
X499051Y-186551D01*
D02*
G37*
G36*
X525949Y-201792D02*
X525233D01*
X524571Y-202066D01*
X524065Y-202572D01*
X523791Y-203234D01*
Y-203950D01*
X524065Y-204612D01*
X524571Y-205118D01*
X525233Y-205392D01*
X525949D01*
X526610Y-205118D01*
X527116Y-204612D01*
X527391Y-203950D01*
Y-203234D01*
X527116Y-202572D01*
X526610Y-202066D01*
X525949Y-201792D01*
D02*
G37*
G36*
X609020Y-240326D02*
X608303D01*
X607642Y-240600D01*
X607135Y-241106D01*
X606861Y-241768D01*
Y-242484D01*
X607135Y-243146D01*
X607642Y-243652D01*
X608303Y-243926D01*
X609020D01*
X609681Y-243652D01*
X610187Y-243146D01*
X610461Y-242484D01*
Y-241768D01*
X610187Y-241106D01*
X609681Y-240600D01*
X609020Y-240326D01*
D02*
G37*
G36*
X587402Y-244242D02*
X587401Y-244242D01*
X579528D01*
X579528Y-244242D01*
X578981Y-244351D01*
X578518Y-244660D01*
X571456Y-251722D01*
X559055D01*
X559055Y-251722D01*
X558509Y-251831D01*
X558046Y-252140D01*
X555618Y-254568D01*
X555309Y-255031D01*
X555200Y-255577D01*
X555200Y-255577D01*
Y-256924D01*
X555102Y-257023D01*
X554828Y-257684D01*
Y-258400D01*
X555102Y-259062D01*
X555608Y-259568D01*
X555661Y-259590D01*
X555779Y-260180D01*
X555561Y-260398D01*
X555287Y-261059D01*
Y-261775D01*
X555557Y-262429D01*
Y-278346D01*
X555674Y-278932D01*
X556005Y-279428D01*
X564882Y-288305D01*
X565378Y-288636D01*
X565963Y-288753D01*
X568536D01*
X569190Y-289023D01*
X569906D01*
X570567Y-288749D01*
X571073Y-288243D01*
X571348Y-287581D01*
Y-286865D01*
X571170Y-286436D01*
X571459Y-285936D01*
X571520D01*
X572182Y-285662D01*
X572688Y-285156D01*
X573229Y-285156D01*
X573277Y-285272D01*
X573783Y-285778D01*
X574445Y-286052D01*
X575161D01*
X575823Y-285778D01*
X576017Y-285584D01*
X576427Y-285665D01*
X576933Y-286172D01*
X577595Y-286446D01*
X578311D01*
X578972Y-286172D01*
X579479Y-285665D01*
X579685Y-285167D01*
X580215Y-284989D01*
X581643Y-286418D01*
Y-292976D01*
X581348Y-293272D01*
X581074Y-293933D01*
Y-294649D01*
X581348Y-295311D01*
X581854Y-295817D01*
X582516Y-296091D01*
X583232D01*
X583894Y-295817D01*
X584400Y-295311D01*
X584674Y-294649D01*
Y-293933D01*
X584498Y-293509D01*
Y-285827D01*
X584498Y-285827D01*
X584390Y-285280D01*
X584080Y-284817D01*
X584080Y-284817D01*
X576206Y-276943D01*
X575743Y-276634D01*
X575197Y-276525D01*
X575197Y-276525D01*
X573032D01*
X564813Y-268306D01*
Y-258992D01*
X564912Y-258894D01*
X565186Y-258232D01*
Y-257795D01*
X565255Y-257719D01*
X565679Y-257499D01*
X565920Y-257599D01*
X566150Y-257971D01*
X566128Y-258185D01*
X565916Y-258697D01*
Y-259413D01*
X566191Y-260075D01*
X566697Y-260581D01*
X567358Y-260855D01*
X568075D01*
X568736Y-260581D01*
X569242Y-260075D01*
X569517Y-259413D01*
Y-258697D01*
X569249Y-258051D01*
X569277Y-257991D01*
X569548Y-257634D01*
X569721Y-257705D01*
X570184D01*
X570500Y-257847D01*
X570641Y-258162D01*
Y-258626D01*
X570915Y-259287D01*
X571013Y-259386D01*
Y-264567D01*
X571013Y-264567D01*
X571122Y-265113D01*
X571432Y-265576D01*
X593479Y-287624D01*
X593942Y-287933D01*
X594488Y-288042D01*
X594488Y-288042D01*
X606889D01*
X610798Y-291951D01*
Y-292090D01*
X611072Y-292752D01*
X611579Y-293258D01*
X612240Y-293532D01*
X612956D01*
X613618Y-293258D01*
X614124Y-292752D01*
X614398Y-292090D01*
Y-291374D01*
X614124Y-290713D01*
X613618Y-290206D01*
X612956Y-289932D01*
X612817D01*
X608490Y-285605D01*
X608027Y-285295D01*
X607480Y-285187D01*
X607480Y-285187D01*
X595080D01*
X573868Y-263976D01*
Y-259386D01*
X573967Y-259287D01*
X574241Y-258626D01*
Y-257910D01*
X573967Y-257248D01*
X573461Y-256742D01*
X572799Y-256468D01*
X572335D01*
X572020Y-256327D01*
X571879Y-256011D01*
Y-255547D01*
X571684Y-255077D01*
X571949Y-254577D01*
X572047D01*
X572047Y-254577D01*
X572593Y-254468D01*
X573057Y-254159D01*
X580119Y-247097D01*
X586810D01*
X616707Y-276994D01*
X616707Y-276994D01*
X617170Y-277303D01*
X617717Y-277412D01*
X617717Y-277412D01*
X627968D01*
X628777Y-278220D01*
Y-278359D01*
X629051Y-279021D01*
X629557Y-279527D01*
X630219Y-279801D01*
X630935D01*
X631596Y-279527D01*
X632102Y-279021D01*
X632377Y-278359D01*
Y-277643D01*
X632102Y-276982D01*
X631596Y-276475D01*
X630935Y-276201D01*
X630795D01*
X629569Y-274975D01*
X629106Y-274665D01*
X628559Y-274557D01*
X628559Y-274557D01*
X618308D01*
X588411Y-244660D01*
X587948Y-244351D01*
X587402Y-244242D01*
D02*
G37*
G36*
X590909Y-240720D02*
X590193D01*
X589532Y-240994D01*
X589025Y-241500D01*
X588751Y-242162D01*
Y-242878D01*
X589025Y-243539D01*
X589532Y-244046D01*
X590193Y-244320D01*
X590909D01*
X591571Y-244046D01*
X592077Y-243539D01*
X592351Y-242878D01*
Y-242162D01*
X592077Y-241500D01*
X591571Y-240994D01*
X590909Y-240720D01*
D02*
G37*
G36*
X605476Y-242688D02*
X604760D01*
X604099Y-242962D01*
X603592Y-243469D01*
X603318Y-244130D01*
Y-244846D01*
X603592Y-245508D01*
X604099Y-246014D01*
X604760Y-246288D01*
X605476D01*
X606138Y-246014D01*
X606644Y-245508D01*
X606918Y-244846D01*
Y-244130D01*
X606644Y-243469D01*
X606138Y-242962D01*
X605476Y-242688D01*
D02*
G37*
G36*
X600358Y-246625D02*
X599642D01*
X598980Y-246899D01*
X598474Y-247406D01*
X598200Y-248067D01*
Y-248783D01*
X598474Y-249445D01*
X598980Y-249951D01*
X599642Y-250225D01*
X600358D01*
X601020Y-249951D01*
X601526Y-249445D01*
X601800Y-248783D01*
Y-248067D01*
X601526Y-247406D01*
X601020Y-246899D01*
X600358Y-246625D01*
D02*
G37*
G36*
X585397Y-247806D02*
X584681D01*
X584020Y-248080D01*
X583513Y-248587D01*
X583239Y-249248D01*
Y-249964D01*
X583513Y-250626D01*
X584020Y-251132D01*
X584681Y-251406D01*
X585397D01*
X586059Y-251132D01*
X586565Y-250626D01*
X586839Y-249964D01*
Y-249248D01*
X586565Y-248587D01*
X586059Y-248080D01*
X585397Y-247806D01*
D02*
G37*
G36*
X624767Y-246232D02*
X624051D01*
X623390Y-246505D01*
X622884Y-247012D01*
X622610Y-247674D01*
Y-248390D01*
X622884Y-249051D01*
X623390Y-249557D01*
X623554Y-249625D01*
X623580Y-249674D01*
X623633Y-250199D01*
X623277Y-250555D01*
X623003Y-251217D01*
Y-251933D01*
X623277Y-252594D01*
X623783Y-253101D01*
X624445Y-253375D01*
X625161D01*
X625823Y-253101D01*
X626329Y-252594D01*
X626603Y-251933D01*
Y-251217D01*
X626329Y-250555D01*
X625823Y-250049D01*
X625659Y-249981D01*
X625632Y-249932D01*
X625580Y-249407D01*
X625935Y-249051D01*
X626209Y-248390D01*
Y-247674D01*
X625935Y-247012D01*
X625429Y-246505D01*
X624767Y-246232D01*
D02*
G37*
G36*
X611775Y-245838D02*
X611059D01*
X610398Y-246112D01*
X609891Y-246618D01*
X609617Y-247280D01*
Y-247996D01*
X609891Y-248657D01*
X610398Y-249164D01*
X611059Y-249438D01*
X611354D01*
X611453Y-249938D01*
X611185Y-250049D01*
X610679Y-250555D01*
X610405Y-251217D01*
Y-251933D01*
X610679Y-252594D01*
X611185Y-253101D01*
X611847Y-253375D01*
X612563D01*
X613224Y-253101D01*
X613731Y-252594D01*
X614005Y-251933D01*
Y-251217D01*
X613731Y-250555D01*
X613224Y-250049D01*
X612563Y-249775D01*
X612268D01*
X612169Y-249275D01*
X612437Y-249164D01*
X612943Y-248657D01*
X613217Y-247996D01*
Y-247280D01*
X612943Y-246618D01*
X612437Y-246112D01*
X611775Y-245838D01*
D02*
G37*
G36*
X585791Y-252137D02*
X585075D01*
X584413Y-252411D01*
X583907Y-252917D01*
X583633Y-253579D01*
Y-254295D01*
X583907Y-254957D01*
X584378Y-255428D01*
X584397Y-255709D01*
X584378Y-255990D01*
X583907Y-256461D01*
X583735Y-256876D01*
X583194D01*
X583022Y-256461D01*
X582516Y-255954D01*
X581854Y-255680D01*
X581138D01*
X580476Y-255954D01*
X580005Y-256425D01*
X579724Y-256444D01*
X579444Y-256425D01*
X578972Y-255954D01*
X578311Y-255680D01*
X577595D01*
X576933Y-255954D01*
X576427Y-256461D01*
X576153Y-257122D01*
Y-257838D01*
X576427Y-258500D01*
X576933Y-259006D01*
X577595Y-259280D01*
X578311D01*
X578972Y-259006D01*
X579444Y-258535D01*
X579724Y-258516D01*
X580005Y-258535D01*
X580476Y-259006D01*
X581138Y-259280D01*
X581854D01*
X582516Y-259006D01*
X583022Y-258500D01*
X583194Y-258085D01*
X583735D01*
X583907Y-258500D01*
X584413Y-259006D01*
X585075Y-259280D01*
X585791D01*
X586453Y-259006D01*
X586959Y-258500D01*
X587233Y-257838D01*
Y-257122D01*
X586959Y-256461D01*
X586488Y-255990D01*
X586469Y-255709D01*
X586488Y-255428D01*
X586959Y-254957D01*
X587233Y-254295D01*
Y-253579D01*
X586959Y-252917D01*
X586453Y-252411D01*
X585791Y-252137D01*
D02*
G37*
G36*
X616893Y-253712D02*
X616177D01*
X615516Y-253986D01*
X615009Y-254492D01*
X614735Y-255154D01*
Y-255870D01*
X615009Y-256531D01*
X615516Y-257038D01*
X616177Y-257312D01*
X616893D01*
X617555Y-257038D01*
X618061Y-256531D01*
X618335Y-255870D01*
Y-255154D01*
X618061Y-254492D01*
X617555Y-253986D01*
X616893Y-253712D01*
D02*
G37*
G36*
X625161Y-254105D02*
X624445D01*
X623783Y-254380D01*
X623277Y-254886D01*
X623003Y-255547D01*
Y-256263D01*
X623277Y-256925D01*
X623783Y-257432D01*
X624445Y-257705D01*
X625161D01*
X625823Y-257432D01*
X626329Y-256925D01*
X626603Y-256263D01*
Y-255547D01*
X626329Y-254886D01*
X625823Y-254380D01*
X625161Y-254105D01*
D02*
G37*
G36*
X544846Y-263948D02*
X544130D01*
X543469Y-264222D01*
X542962Y-264728D01*
X542688Y-265390D01*
Y-266106D01*
X542962Y-266768D01*
X543469Y-267274D01*
X544130Y-267548D01*
X544846D01*
X545508Y-267274D01*
X546014Y-266768D01*
X546288Y-266106D01*
Y-265390D01*
X546014Y-264728D01*
X545508Y-264222D01*
X544846Y-263948D01*
D02*
G37*
G36*
X588547Y-261586D02*
X587831D01*
X587169Y-261860D01*
X586663Y-262366D01*
X586389Y-263028D01*
Y-263744D01*
X586663Y-264405D01*
X587169Y-264912D01*
X587831Y-265186D01*
X588547D01*
X588720Y-265114D01*
X588991Y-265471D01*
X589019Y-265532D01*
X588751Y-266177D01*
Y-266894D01*
X589025Y-267555D01*
X589532Y-268061D01*
X590193Y-268335D01*
X590909D01*
X591571Y-268061D01*
X592077Y-267555D01*
X592351Y-266894D01*
Y-266177D01*
X592077Y-265516D01*
X591571Y-265009D01*
X590909Y-264735D01*
X590193D01*
X590021Y-264807D01*
X589749Y-264450D01*
X589721Y-264390D01*
X589989Y-263744D01*
Y-263028D01*
X589715Y-262366D01*
X589209Y-261860D01*
X588547Y-261586D01*
D02*
G37*
G36*
X545634Y-273397D02*
X544918D01*
X544256Y-273671D01*
X543750Y-274177D01*
X543476Y-274839D01*
Y-275555D01*
X543750Y-276217D01*
X544256Y-276723D01*
X544918Y-276997D01*
X545634D01*
X546295Y-276723D01*
X546802Y-276217D01*
X547076Y-275555D01*
Y-274839D01*
X546802Y-274177D01*
X546295Y-273671D01*
X545634Y-273397D01*
D02*
G37*
G36*
X545486Y-279072D02*
X544770D01*
X544108Y-279346D01*
X543602Y-279853D01*
X543328Y-280514D01*
Y-281230D01*
X543602Y-281892D01*
X544108Y-282398D01*
X544770Y-282672D01*
X545486D01*
X546147Y-282398D01*
X546654Y-281892D01*
X546928Y-281230D01*
Y-280514D01*
X546654Y-279853D01*
X546147Y-279346D01*
X545486Y-279072D01*
D02*
G37*
G36*
X640122Y-282058D02*
X639406D01*
X638744Y-282332D01*
X638238Y-282839D01*
X637964Y-283500D01*
Y-284216D01*
X638238Y-284878D01*
X638744Y-285384D01*
X639406Y-285658D01*
X640122D01*
X640783Y-285384D01*
X641290Y-284878D01*
X641564Y-284216D01*
Y-283500D01*
X641290Y-282839D01*
X640783Y-282332D01*
X640122Y-282058D01*
D02*
G37*
G36*
X545267Y-285637D02*
X544551D01*
X543889Y-285911D01*
X543383Y-286417D01*
X543109Y-287079D01*
Y-287795D01*
X543383Y-288456D01*
X543889Y-288963D01*
X544551Y-289237D01*
X545267D01*
X545929Y-288963D01*
X546435Y-288456D01*
X546709Y-287795D01*
Y-287079D01*
X546435Y-286417D01*
X545929Y-285911D01*
X545267Y-285637D01*
D02*
G37*
G36*
X595634Y-289932D02*
X594918D01*
X594256Y-290206D01*
X593750Y-290713D01*
X593476Y-291374D01*
Y-292090D01*
X593750Y-292752D01*
X594256Y-293258D01*
X594918Y-293532D01*
X595634D01*
X596295Y-293258D01*
X596802Y-292752D01*
X597076Y-292090D01*
Y-291374D01*
X596802Y-290713D01*
X596295Y-290206D01*
X595634Y-289932D01*
D02*
G37*
G36*
X545634Y-292295D02*
X544918D01*
X544256Y-292568D01*
X543750Y-293075D01*
X543476Y-293737D01*
Y-294453D01*
X543750Y-295114D01*
X544256Y-295620D01*
X544918Y-295895D01*
X545634D01*
X546295Y-295620D01*
X546802Y-295114D01*
X547076Y-294453D01*
Y-293737D01*
X546802Y-293075D01*
X546295Y-292568D01*
X545634Y-292295D01*
D02*
G37*
G36*
X555082Y-293082D02*
X554366D01*
X553705Y-293356D01*
X553198Y-293862D01*
X552924Y-294524D01*
Y-295240D01*
X553198Y-295901D01*
X553705Y-296408D01*
X554366Y-296682D01*
X555082D01*
X555744Y-296408D01*
X556250Y-295901D01*
X556524Y-295240D01*
Y-294524D01*
X556250Y-293862D01*
X555744Y-293356D01*
X555082Y-293082D01*
D02*
G37*
G36*
X565712Y-291113D02*
X564996D01*
X564335Y-291387D01*
X563828Y-291894D01*
X563554Y-292555D01*
Y-293271D01*
X563828Y-293933D01*
X564335Y-294439D01*
X564988Y-294710D01*
X569785Y-299507D01*
X570281Y-299838D01*
X570866Y-299955D01*
X590551D01*
X591136Y-299838D01*
X591633Y-299507D01*
X593153Y-297986D01*
X626548D01*
X627201Y-298257D01*
X627917D01*
X628579Y-297983D01*
X629085Y-297476D01*
X629359Y-296815D01*
Y-296099D01*
X629085Y-295437D01*
X628579Y-294931D01*
X627917Y-294657D01*
X627201D01*
X626548Y-294927D01*
X592520D01*
X591934Y-295044D01*
X591438Y-295375D01*
X589918Y-296896D01*
X571500D01*
X567151Y-292547D01*
X566880Y-291894D01*
X566374Y-291387D01*
X565712Y-291113D01*
D02*
G37*
G36*
X638153Y-295838D02*
X637437D01*
X636776Y-296112D01*
X636269Y-296618D01*
X635995Y-297280D01*
Y-297996D01*
X636269Y-298657D01*
X636776Y-299164D01*
X637437Y-299438D01*
X638153D01*
X638815Y-299164D01*
X639321Y-298657D01*
X639595Y-297996D01*
Y-297280D01*
X639321Y-296618D01*
X638815Y-296112D01*
X638153Y-295838D01*
D02*
G37*
G36*
X616106Y-303712D02*
X615390D01*
X614728Y-303986D01*
X614222Y-304492D01*
X613948Y-305154D01*
Y-305870D01*
X614222Y-306531D01*
X614728Y-307038D01*
X615390Y-307312D01*
X616106D01*
X616768Y-307038D01*
X617274Y-306531D01*
X617548Y-305870D01*
Y-305154D01*
X617274Y-304492D01*
X616768Y-303986D01*
X616106Y-303712D01*
D02*
G37*
G36*
X562956Y-304893D02*
X562240D01*
X561579Y-305167D01*
X561072Y-305673D01*
X560798Y-306335D01*
Y-307051D01*
X561072Y-307713D01*
X561579Y-308219D01*
X562240Y-308493D01*
X562956D01*
X563618Y-308219D01*
X564124Y-307713D01*
X564398Y-307051D01*
Y-306335D01*
X564124Y-305673D01*
X563618Y-305167D01*
X562956Y-304893D01*
D02*
G37*
%LPD*%
D12*
X260561Y-390826D02*
G03*
X259287Y-390247I-1413J-1416D01*
G01*
X215115Y-391673D02*
G03*
X214252Y-393318I1137J-1645D01*
G01*
X664961Y-325984D02*
X674409Y-316535D01*
Y-288976D01*
X685827Y-277559D01*
Y-203937D01*
X681890Y-200000D02*
X685827Y-203937D01*
X539900Y-140766D02*
X543701Y-144566D01*
Y-164567D02*
Y-144566D01*
X538583Y-169685D02*
X543701Y-164567D01*
X538583Y-201969D02*
Y-169685D01*
Y-201969D02*
X542126Y-205512D01*
X544882D01*
X547244Y-203150D01*
X159134Y-404100D02*
Y-390901D01*
X155197Y-389452D02*
X156441Y-388208D01*
X159134Y-390901D01*
X155197Y-404100D02*
Y-389452D01*
X163071Y-404100D02*
Y-390730D01*
X277289Y-404055D02*
Y-401303D01*
X259285Y-390247D02*
X259287Y-390247D01*
X260561Y-390826D02*
X260562Y-390828D01*
X226063Y-404100D02*
Y-390722D01*
X233937Y-404100D02*
Y-391623D01*
X214252Y-393318D02*
Y-393318D01*
Y-404100D02*
Y-393318D01*
X202441Y-404100D02*
Y-390600D01*
X260562Y-390828D02*
X261343Y-391608D01*
X215115Y-391673D02*
X216162Y-390947D01*
X233937Y-391623D02*
X235144Y-390416D01*
X251378Y-390009D02*
X251456D01*
X277387Y-392067D02*
X279445Y-390009D01*
X281201D01*
X264954Y-401027D02*
Y-392780D01*
X249730Y-391658D02*
X251378Y-390009D01*
X245669Y-391181D02*
X246841Y-390009D01*
X263783Y-391608D02*
X264954Y-392780D01*
X277289Y-401303D02*
X277387Y-401205D01*
X264954Y-401027D02*
X265354Y-401427D01*
X245669D02*
Y-391181D01*
X246841Y-390009D02*
X251378D01*
X261343Y-401353D02*
X261417Y-401427D01*
X261343Y-401353D02*
Y-391608D01*
X263783D01*
X277387Y-401205D02*
Y-392067D01*
X277244Y-404100D02*
X277289Y-404055D01*
X249730Y-401303D02*
Y-391658D01*
X249606Y-401427D02*
X249730Y-401303D01*
X277165Y-401427D02*
X277289Y-401303D01*
X186571Y-403978D02*
Y-389966D01*
X182941Y-386336D02*
X186571Y-389966D01*
X182677Y-389616D02*
X182677Y-389616D01*
Y-401427D02*
Y-389616D01*
X186571Y-403978D02*
X186693Y-404100D01*
D14*
X256897Y-112788D02*
Y-112001D01*
X246063Y-123622D02*
X256897Y-112788D01*
X239370Y-123622D02*
X246063D01*
X239370Y-127953D02*
Y-123622D01*
Y-127953D02*
X240945Y-129528D01*
X633574Y-214676D02*
X635039Y-216142D01*
X618748Y-214676D02*
X633574D01*
X604331Y-200259D02*
X618748Y-214676D01*
X604331Y-200259D02*
Y-196063D01*
X599606Y-191339D02*
X604331Y-196063D01*
X572047Y-191339D02*
X599606D01*
X569291Y-194095D02*
X572047Y-191339D01*
X608661Y-236221D02*
Y-227953D01*
X600000Y-219291D02*
X608661Y-227953D01*
X587008Y-219291D02*
X600000D01*
X573622Y-205906D02*
X587008Y-219291D01*
X573622Y-205906D02*
Y-198819D01*
X565354Y-292913D02*
X570866Y-298425D01*
X590551D01*
X592520Y-296457D01*
X627559D01*
X557087Y-278346D02*
Y-261417D01*
Y-278346D02*
X565963Y-287223D01*
X569548D01*
X240945Y-309638D02*
Y-129528D01*
Y-309638D02*
X258472Y-327165D01*
D19*
X218439Y-374114D02*
G03*
X218310Y-374444I371J-335D01*
G01*
X206441Y-378907D02*
G03*
X206496Y-378774I-133J133D01*
G01*
X269496Y-374321D02*
G03*
X269488Y-374409I492J-88D01*
G01*
X269441Y-378907D02*
G03*
X269488Y-378793I-114J114D01*
G01*
X237941Y-378907D02*
G03*
X237992Y-378783I-124J124D01*
G01*
X253346Y-378679D02*
G03*
X253441Y-378907I323J0D01*
G01*
X256890Y-378783D02*
G03*
X256941Y-378907I175J0D01*
G01*
X253655Y-374421D02*
G03*
X253346Y-374879I191J-462D01*
G01*
X241811Y-404100D02*
G03*
X241941Y-403786I-314J314D01*
G01*
X273441Y-382293D02*
G03*
X273307Y-382616I323J-323D01*
G01*
X269441Y-382293D02*
G03*
X269370Y-382464I171J-171D01*
G01*
X256941Y-400125D02*
G03*
X257480Y-401427I1841J0D01*
G01*
X253622Y-382730D02*
G03*
X253441Y-382293I-618J0D01*
G01*
Y-401180D02*
G03*
X253543Y-401427I349J0D01*
G01*
X206441Y-382293D02*
G03*
X206378Y-382445I152J-152D01*
G01*
X206299Y-401427D02*
G03*
X206441Y-401085I-342J342D01*
G01*
X210236Y-401427D02*
G03*
X210441Y-400933I-494J494D01*
G01*
X218110Y-401427D02*
G03*
X218341Y-400870I-557J557D01*
G01*
X222047Y-401427D02*
G03*
X222641Y-399993I-1433J1433D01*
G01*
X237795Y-401427D02*
G03*
X237941Y-401075I-352J352D01*
G01*
X241732Y-401427D02*
G03*
X241941Y-400923I-504J504D01*
G01*
X273228Y-401427D02*
G03*
X273441Y-400913I-514J514D01*
G01*
X269291Y-401427D02*
G03*
X269441Y-401065I-362J362D01*
G01*
X269370Y-404100D02*
G03*
X269441Y-403929I-171J171D01*
G01*
X218189Y-404100D02*
G03*
X218341Y-403733I-367J367D01*
G01*
X237874Y-404100D02*
G03*
X237941Y-403938I-162J162D01*
G01*
X256941Y-402608D02*
G03*
X257557Y-404098I2110J0D01*
G01*
D02*
G03*
X257559Y-404100I1494J1490D01*
G01*
X218307Y-374706D02*
X218310Y-374444D01*
X218439Y-374114D02*
X218444Y-374109D01*
X218445Y-374108D01*
X218307Y-378873D02*
X218341Y-378907D01*
X218307Y-378873D02*
Y-374706D01*
X222638Y-378904D02*
Y-374655D01*
Y-378904D02*
X222641Y-378907D01*
X206496Y-378774D02*
Y-374655D01*
X210433Y-378899D02*
Y-374655D01*
Y-378899D02*
X210441Y-378907D01*
X269496Y-374321D02*
X269501Y-374292D01*
X269488Y-378793D02*
Y-374409D01*
X269501Y-374292D02*
X269502Y-374291D01*
X273425Y-378891D02*
Y-374655D01*
Y-378891D02*
X273441Y-378907D01*
X237992Y-378783D02*
Y-374655D01*
X241929Y-378895D02*
Y-374655D01*
Y-378895D02*
X241941Y-378907D01*
X253346Y-378679D02*
Y-374879D01*
X256890Y-378783D02*
Y-374655D01*
X273441Y-400913D02*
Y-382293D01*
X269441Y-401065D02*
Y-382293D01*
X256941Y-400125D02*
Y-382293D01*
X253441Y-401180D02*
Y-382293D01*
X206441Y-401085D02*
Y-382293D01*
X210441Y-400933D02*
Y-382293D01*
X218341Y-400870D02*
Y-382293D01*
X222641Y-399993D02*
Y-382293D01*
X237941Y-401075D02*
Y-382293D01*
X241941Y-400923D02*
Y-382293D01*
D24*
X369921Y-212598D02*
G03*
X379921Y-202598I0J10000D01*
G01*
X322441Y-212598D02*
G03*
X314503Y-220537I0J-7938D01*
G01*
X371031Y-210630D02*
G03*
X377921Y-203740I0J6890D01*
G01*
X321811Y-210630D02*
G03*
X311811Y-220630I0J-10000D01*
G01*
X548443Y-210697D02*
X549213Y-211466D01*
X475361Y-137615D02*
X533514Y-195768D01*
Y-204774D02*
Y-195768D01*
Y-204774D02*
X539437Y-210697D01*
X548443D01*
X460186Y-175448D02*
X464374Y-171260D01*
X471260D01*
X473228Y-173228D01*
X476945D01*
X568504Y-88189D02*
X569685Y-89370D01*
X570472D01*
X572835Y-91732D01*
Y-108268D02*
Y-91732D01*
X567410Y-113692D02*
X572835Y-108268D01*
X567410Y-237708D02*
Y-113692D01*
X546850Y-258268D02*
X567410Y-237708D01*
X520079Y-258268D02*
X546850D01*
X516929Y-255118D02*
X520079Y-258268D01*
X381102Y-255118D02*
X516929D01*
X363731Y-272490D02*
X381102Y-255118D01*
X360236Y-272490D02*
X363731D01*
X568504Y-88189D02*
X575915Y-80778D01*
X578168D01*
X475984Y-127165D02*
Y-125591D01*
X473622Y-123228D02*
Y-120866D01*
Y-123228D02*
X475984Y-125591D01*
X456742Y-122884D02*
Y-116043D01*
Y-122884D02*
X464173Y-130315D01*
X470866D01*
X472916Y-132365D01*
X480120D01*
X463551Y-121819D02*
Y-116025D01*
Y-121819D02*
X468898Y-127165D01*
X475984D01*
X473622Y-120866D02*
X474803Y-119685D01*
X480315D01*
X499606Y-100394D01*
X533465D01*
X541339Y-108268D01*
Y-113623D02*
Y-108268D01*
X539233Y-115729D02*
X541339Y-113623D01*
X480120Y-132365D02*
Y-125392D01*
X491339Y-114173D01*
X505118D01*
X512598Y-106693D01*
X535827D01*
X538583Y-109449D01*
Y-111811D02*
Y-109449D01*
X532677Y-111811D02*
X538583D01*
X529921Y-114567D02*
X532677Y-111811D01*
X529921Y-120521D02*
Y-114567D01*
X524606Y-125836D02*
X529921Y-120521D01*
X539233Y-125728D02*
Y-115729D01*
X534252Y-130709D02*
X539233Y-125728D01*
X531102Y-130709D02*
X534252D01*
X529134Y-128740D02*
X531102Y-130709D01*
X524557Y-128740D02*
X529134D01*
X524557Y-132529D02*
Y-128740D01*
X520866Y-136221D02*
X524557Y-132529D01*
X520866Y-161417D02*
Y-136221D01*
Y-161417D02*
X523622Y-164173D01*
X525984D01*
X533044Y-171233D01*
Y-176225D02*
Y-171233D01*
X524458Y-125984D02*
X524606Y-125836D01*
X521260Y-125984D02*
X524458D01*
X510236Y-137008D02*
X521260Y-125984D01*
X510236Y-165748D02*
Y-137008D01*
Y-165748D02*
X511417Y-166929D01*
X523969D01*
X530027Y-172987D01*
X450850Y-177227D02*
X495669Y-222047D01*
X450850Y-177227D02*
Y-174127D01*
X457283Y-179724D02*
X500394Y-222835D01*
X457283Y-179724D02*
Y-175147D01*
X588372Y-100945D02*
X591575D01*
X596457Y-96063D01*
X599213D01*
X603937Y-91339D01*
Y-76378D01*
X612598Y-67716D01*
X625984D01*
X628740Y-64961D01*
Y-59498D01*
X658465Y-29773D01*
X644636Y-21899D02*
X658465D01*
X597227Y-69308D02*
X644636Y-21899D01*
X597227Y-77103D02*
Y-69308D01*
X608661Y-103937D02*
X612598Y-100000D01*
X581890Y-103937D02*
X608661D01*
X579921Y-101969D02*
X581890Y-103937D01*
X241732Y-121653D02*
X246063Y-117323D01*
X237402Y-318094D02*
Y-122441D01*
X238189Y-121653D02*
X241732D01*
X237402Y-122441D02*
X238189Y-121653D01*
X246063Y-117323D02*
Y-111024D01*
X181232Y-65797D02*
X201723Y-86288D01*
X267016Y-182806D02*
X373057D01*
X201723Y-86288D02*
X234713D01*
X259842Y-111417D01*
Y-175633D02*
Y-111417D01*
Y-175633D02*
X267016Y-182806D01*
X175197Y-57923D02*
X201332Y-84058D01*
X268472Y-181506D02*
X373618D01*
X201332Y-84058D02*
X234839D01*
X235039Y-83858D01*
X262598Y-111417D01*
Y-175633D02*
Y-111417D01*
Y-175633D02*
X268472Y-181506D01*
X157350Y-38238D02*
X200990Y-81877D01*
X270802Y-180206D02*
X374157D01*
X200990Y-81877D02*
X235814D01*
X265354Y-111417D01*
Y-174759D02*
Y-111417D01*
Y-174759D02*
X270802Y-180206D01*
X577953Y-83858D02*
X579921Y-85827D01*
Y-101969D02*
Y-85827D01*
X612205Y-87008D02*
X612598Y-87402D01*
Y-100000D02*
Y-87402D01*
X667717Y-106693D02*
X673228Y-101181D01*
Y-70866D01*
X674409Y-69685D01*
X683858D01*
X687378Y-66165D01*
X689466D01*
X679517Y-63619D02*
X680082Y-64183D01*
X679517Y-63619D02*
Y-37023D01*
X683127Y-46745D02*
X686319Y-43553D01*
X683127Y-66209D02*
Y-46745D01*
X565202Y-144095D02*
Y-123622D01*
X607480Y-286614D02*
X612598Y-291732D01*
X594488Y-286614D02*
X607480D01*
X572441Y-264567D02*
X594488Y-286614D01*
X572441Y-264567D02*
Y-258268D01*
X628559Y-275984D02*
X630577Y-278001D01*
X617717Y-275984D02*
X628559D01*
X587402Y-245669D02*
X617717Y-275984D01*
X579528Y-245669D02*
X587402D01*
X572047Y-253150D02*
X579528Y-245669D01*
X559055Y-253150D02*
X572047D01*
X556628Y-255577D02*
X559055Y-253150D01*
X556628Y-258042D02*
Y-255577D01*
X582874Y-294291D02*
X583071Y-294094D01*
Y-285827D01*
X575197Y-277953D02*
X583071Y-285827D01*
X572441Y-277953D02*
X575197D01*
X563386Y-268898D02*
X572441Y-277953D01*
X563386Y-268898D02*
Y-257874D01*
X71850Y-38238D02*
X157350D01*
X99410Y-57923D02*
X175197D01*
X99410Y-65797D02*
X181232D01*
X142520Y-156693D02*
X144871Y-154342D01*
Y-131609D01*
X311811Y-225427D02*
X314417Y-228033D01*
X311811Y-225427D02*
Y-220630D01*
X310525Y-231391D02*
X314623D01*
X307480Y-228346D02*
X310525Y-231391D01*
X565202Y-232829D02*
Y-144095D01*
Y-123622D02*
Y-25789D01*
X542491Y-237947D02*
X552362Y-228076D01*
Y-12992D01*
X544291Y-4921D02*
X552362Y-12992D01*
X336261Y-249647D02*
X545628D01*
X563902Y-231373D02*
Y-21216D01*
X545628Y-249647D02*
X563902Y-231373D01*
X328740Y-250984D02*
X547047D01*
X565202Y-232829D01*
X371228Y-200000D02*
X372016Y-200787D01*
X322047Y-200000D02*
X371228D01*
X307480Y-214567D02*
X322047Y-200000D01*
X307480Y-228346D02*
Y-214567D01*
X322441Y-212598D02*
X369921D01*
X314503Y-225180D02*
Y-220537D01*
X379921Y-202598D02*
Y-201740D01*
X321811Y-210630D02*
X371031D01*
X237402Y-318094D02*
X246472Y-327165D01*
X329819Y-243205D02*
X336261Y-249647D01*
X325787Y-243205D02*
X329819D01*
X321850Y-244094D02*
X328740Y-250984D01*
X563902Y-21216D02*
X589055Y3937D01*
X565202Y-25789D02*
X593208Y2217D01*
Y9784D01*
X589055Y13937D02*
X593208Y9784D01*
X321850Y-244094D02*
Y-235236D01*
X323724Y-233362D01*
X325787D01*
X80596Y-142270D02*
X95250D01*
X97409Y-140111D01*
X105409Y-143458D02*
Y-140111D01*
X101409Y-142561D02*
Y-140111D01*
X109409Y-143135D02*
Y-140111D01*
X65945Y-44143D02*
X71850Y-38238D01*
X323882Y-241205D02*
X329657D01*
X329496Y-239205D02*
X337338Y-247047D01*
X329657Y-241205D02*
X336800Y-248347D01*
X337338Y-247047D02*
X540744D01*
X336800Y-248347D02*
X541283D01*
X323850Y-237205D02*
X329334D01*
X325787Y-239205D02*
X329496D01*
X329334Y-237205D02*
X337877Y-245747D01*
X540206D01*
X420541Y-226591D02*
X543276D01*
X374157Y-180206D02*
X420541Y-226591D01*
X323819Y-227362D02*
X414444D01*
X425029Y-237947D01*
X544294Y-224265D02*
X545276Y-225246D01*
X544089Y-229106D02*
X545276Y-227920D01*
Y-225246D01*
X549213Y-228346D02*
Y-211466D01*
X544291Y-233268D02*
X549213Y-228346D01*
X420657Y-230406D02*
X545184D01*
X547913Y-227678D02*
Y-219024D01*
X545184Y-230406D02*
X547913Y-227678D01*
X544294Y-224265D02*
Y-224248D01*
X421218Y-229106D02*
X544089D01*
X543029Y-239247D02*
X557402Y-224874D01*
X560002Y-225951D02*
Y-14857D01*
X562602Y-227028D02*
Y-17976D01*
X540206Y-245747D02*
X560002Y-225951D01*
X557402Y-224874D02*
Y-16064D01*
X543568Y-240547D02*
X558702Y-225412D01*
X540744Y-247047D02*
X561302Y-226489D01*
X423952Y-240547D02*
X543568D01*
X558702Y-225412D02*
Y-15395D01*
X424491Y-239247D02*
X543029D01*
X541283Y-248347D02*
X562602Y-227028D01*
X561302Y-226489D02*
Y-17438D01*
X425029Y-237947D02*
X542491D01*
X544291Y-215403D02*
X547913Y-219024D01*
X325787Y-229362D02*
X414606D01*
X424491Y-239247D01*
X323882Y-231362D02*
X414767D01*
X423952Y-240547D01*
X-23622Y-184055D02*
X39110D01*
X70495Y-152670D01*
X544291Y5906D02*
X547244Y8858D01*
X553976D02*
X559055Y13937D01*
X547244Y8858D02*
X553976D01*
X544291Y-4921D02*
Y5906D01*
X554528Y-11220D02*
X558702Y-15395D01*
X559055Y-13909D02*
X560002Y-14857D01*
X562602Y-17976D02*
X579055Y-1524D01*
X553208Y-11869D02*
X557402Y-16064D01*
X561302Y-17438D02*
X569055Y-9685D01*
X559055Y-13909D02*
Y5979D01*
X569055Y-9685D02*
Y3937D01*
X579055Y-1524D02*
Y3937D01*
X554528Y-11220D02*
Y5660D01*
X553208Y-11869D02*
Y6179D01*
X556419Y9390D01*
X323850Y-241173D02*
X323882Y-241205D01*
X323819Y-231299D02*
X323882Y-231362D01*
X373618Y-181506D02*
X421218Y-229106D01*
X373057Y-182806D02*
X420657Y-230406D01*
X554528Y5660D02*
X556957Y8090D01*
X569055Y12555D02*
Y13937D01*
X566947Y10447D02*
X569055Y12555D01*
X566947Y10392D02*
Y10447D01*
X565945Y9390D02*
X566947Y10392D01*
X556419Y9390D02*
X565945D01*
X556957Y8090D02*
X576556D01*
X578250Y9784D01*
Y13132D02*
X579055Y13937D01*
X578250Y9784D02*
Y13132D01*
X13780Y-335630D02*
X29880Y-319529D01*
X-23622Y-342520D02*
X10567D01*
X32480Y-320606D01*
X31180Y-320068D02*
Y-206693D01*
X-23622Y-335630D02*
X13780D01*
X29880Y-319529D02*
Y-206154D01*
X-23622Y-339567D02*
X11681D01*
X31180Y-320068D01*
X32480Y-320606D02*
Y-207231D01*
X10827Y-237205D02*
X24680Y-223351D01*
X-23622Y-237205D02*
X10827D01*
X22080Y-222274D02*
Y-202923D01*
X-23622Y-229331D02*
X15024D01*
X24680Y-223351D02*
Y-204000D01*
X-23622Y-233268D02*
X12925D01*
X23380Y-222813D02*
Y-203462D01*
X12925Y-233268D02*
X23380Y-222813D01*
X15024Y-229331D02*
X22080Y-222274D01*
X27280Y-273771D02*
Y-205077D01*
X25980Y-273232D02*
Y-204539D01*
X28580Y-205616D02*
X73726Y-160470D01*
X16732Y-282480D02*
X25980Y-273232D01*
Y-204539D02*
X72649Y-157870D01*
X14634Y-286417D02*
X27280Y-273771D01*
X23380Y-203462D02*
X71572Y-155270D01*
X12535Y-290354D02*
X28580Y-274309D01*
X32480Y-207231D02*
X75341Y-164370D01*
X31180Y-206693D02*
X74803Y-163070D01*
X28580Y-274309D02*
Y-205616D01*
X24680Y-204000D02*
X72110Y-156570D01*
X27280Y-205077D02*
X73187Y-159170D01*
X29880Y-206154D02*
X74264Y-161770D01*
X22080Y-202923D02*
X71034Y-153970D01*
X-23622Y-282480D02*
X16732D01*
X-23622Y-290354D02*
X12535D01*
X-23622Y-286417D02*
X14634D01*
X72649Y-157870D02*
X107544D01*
X72110Y-156570D02*
X107005D01*
X71572Y-155270D02*
X106467D01*
X-23622Y-181102D02*
X40224D01*
X74803Y-163070D02*
X109698D01*
X73726Y-160470D02*
X108621D01*
X74264Y-161770D02*
X109159D01*
X73187Y-159170D02*
X108082D01*
X69957Y-151370D02*
X104851D01*
X69418Y-150070D02*
X104313D01*
X75341Y-164370D02*
X110236D01*
X71034Y-153970D02*
X105929D01*
X40224Y-181102D02*
X69957Y-151370D01*
X42323Y-177165D02*
X69418Y-150070D01*
X-23622Y-177165D02*
X42323D01*
X70495Y-152670D02*
X105390D01*
X-23622Y-102362D02*
X35173D01*
X-23622Y-62992D02*
X-520D01*
X-23622Y-60039D02*
X-1634D01*
X80058Y-143570D02*
X97572D01*
X-520Y-62992D02*
X80058Y-143570D01*
X39370Y-110236D02*
X77904Y-148770D01*
X35173Y-102362D02*
X78981Y-146170D01*
X37272Y-106299D02*
X78442Y-147470D01*
X78981Y-146170D02*
X102698D01*
X-23622Y-66929D02*
X1578D01*
X78442Y-147470D02*
X103236D01*
X-23622Y-110236D02*
X39370D01*
X79519Y-144870D02*
X99100D01*
X77904Y-148770D02*
X103775D01*
X-1634Y-60039D02*
X80596Y-142270D01*
X-23622Y-106299D02*
X37272D01*
X1578Y-66929D02*
X79519Y-144870D01*
X102698Y-146170D02*
X105409Y-143458D01*
X103236Y-147470D02*
X107256Y-143450D01*
Y-141885D01*
X107409Y-141732D01*
X131258Y-139671D02*
Y-123124D01*
X123458Y-136440D02*
Y-126411D01*
X127358Y-138056D02*
Y-124740D01*
X132558Y-140210D02*
Y-122586D01*
X124758Y-136979D02*
Y-125817D01*
X117126Y-137257D02*
Y-132047D01*
X104851Y-151370D02*
X120858Y-135363D01*
X109698Y-163070D02*
X132558Y-140210D01*
X104313Y-150070D02*
X117126Y-137257D01*
X105390Y-152670D02*
X122158Y-135902D01*
X109159Y-161770D02*
X131258Y-139671D01*
X108082Y-159170D02*
X128658Y-138594D01*
X122158Y-135902D02*
Y-130032D01*
X120858Y-135363D02*
Y-131810D01*
X107005Y-156570D02*
X126058Y-137517D01*
Y-125278D01*
X108621Y-160470D02*
X129958Y-139133D01*
X133858Y-140748D02*
Y-122047D01*
X129958Y-139133D02*
Y-123663D01*
X105929Y-153970D02*
X123458Y-136440D01*
X106467Y-155270D02*
X124758Y-136979D01*
X103775Y-148770D02*
X109409Y-143135D01*
X107544Y-157870D02*
X127358Y-138056D01*
X110236Y-164370D02*
X133858Y-140748D01*
X128658Y-138594D02*
Y-124201D01*
X99100Y-144870D02*
X101409Y-142561D01*
X97572Y-143570D02*
X99410Y-141732D01*
X121095Y-122153D02*
X124758Y-125817D01*
X119095Y-130047D02*
X120858Y-131810D01*
X120702Y-119921D02*
X126058Y-125278D01*
X120173Y-128047D02*
X122158Y-130032D01*
X114693Y-110236D02*
X128658Y-124201D01*
X114823Y-112205D02*
X127358Y-124740D01*
X113579Y-107283D02*
X129958Y-123663D01*
X114081Y-105947D02*
X131258Y-123124D01*
X114619Y-104647D02*
X132558Y-122586D01*
X115157Y-103347D02*
X133858Y-122047D01*
X121094Y-124047D02*
X123458Y-126411D01*
X117126Y-128047D02*
X120173D01*
X117126Y-124047D02*
X121094D01*
X107346Y-110236D02*
X114693D01*
X104553Y-105947D02*
X114081D01*
X119201Y-122153D02*
X121095D01*
X109441Y-112205D02*
X114823D01*
X119095Y-122047D02*
X119201Y-122153D01*
X103347Y-103347D02*
X115157D01*
X107283Y-107283D02*
X113579D01*
X117126Y-119921D02*
X120702D01*
X104015Y-104647D02*
X114619D01*
X97284Y-109409D02*
X103347Y-103347D01*
X97284Y-112205D02*
Y-109409D01*
X99499Y-110083D02*
Y-109162D01*
X101347Y-112142D02*
Y-109153D01*
X99347Y-110236D02*
X99499Y-110083D01*
Y-109162D02*
X104015Y-104647D01*
X101347Y-109153D02*
X104553Y-105947D01*
X105347Y-109221D02*
X107283Y-107283D01*
X105347Y-112205D02*
Y-109221D01*
X101284Y-112205D02*
X101347Y-112142D01*
X109409Y-112236D02*
X109441Y-112205D01*
X469521Y-137615D02*
X475361D01*
X190354Y-401230D02*
Y-377411D01*
Y-401230D02*
X190551Y-401427D01*
X158736Y-377411D02*
X178543D01*
X151260Y-402150D02*
X151753Y-401657D01*
Y-384394D02*
X158736Y-377411D01*
X151753Y-401657D02*
Y-384394D01*
X464328Y-146397D02*
X464448Y-146516D01*
X65945Y-50049D02*
Y-44143D01*
X241811Y-404100D02*
X241941Y-403970D01*
X206378Y-404100D02*
X206441Y-404037D01*
X273307Y-404100D02*
X273441Y-403966D01*
D82*
Y-382293D02*
D03*
Y-378907D02*
D03*
X206441D02*
D03*
Y-382293D02*
D03*
X210441D02*
D03*
Y-378907D02*
D03*
X218341D02*
D03*
Y-382293D02*
D03*
X222641D02*
D03*
Y-378907D02*
D03*
X237941Y-382293D02*
D03*
Y-378907D02*
D03*
X241941Y-382293D02*
D03*
Y-378907D02*
D03*
X253441Y-382293D02*
D03*
Y-378907D02*
D03*
X256941D02*
D03*
Y-382293D02*
D03*
X269441D02*
D03*
Y-378907D02*
D03*
D128*
X281102Y-401427D02*
D03*
X159055D02*
D03*
X155118D02*
D03*
X186614D02*
D03*
X182677D02*
D03*
X241732D02*
D03*
X273228D02*
D03*
X269291D02*
D03*
X257480D02*
D03*
X237795D02*
D03*
X253543D02*
D03*
X222047D02*
D03*
X218110D02*
D03*
X210236D02*
D03*
X206299D02*
D03*
X190551D02*
D03*
X166929D02*
D03*
X170866D02*
D03*
X174803D02*
D03*
X178740D02*
D03*
X229921D02*
D03*
X214173D02*
D03*
X202362D02*
D03*
X249606D02*
D03*
X265354D02*
D03*
X245669D02*
D03*
X277165D02*
D03*
X261417D02*
D03*
X233858D02*
D03*
X225984D02*
D03*
X162992D02*
D03*
D129*
X151181Y-399477D02*
D03*
D155*
X692421Y-105610D02*
D03*
Y-72342D02*
D03*
D212*
X695866Y-105610D02*
D03*
Y-72342D02*
D03*
X688976D02*
D03*
Y-105610D02*
D03*
D213*
X682283Y-74803D02*
D03*
Y-103150D02*
D03*
D214*
X672401Y-135695D02*
D03*
D215*
X643701Y-127445D02*
D03*
D216*
Y-143945D02*
D03*
X622001Y-127445D02*
D03*
Y-143945D02*
D03*
D239*
X181496Y-120079D02*
D03*
D240*
X171496D02*
D03*
X161496D02*
D03*
X151496D02*
D03*
X141496D02*
D03*
D241*
X270472Y-327165D02*
D03*
X282283D02*
D03*
X142520Y-156693D02*
D03*
X294094Y-327165D02*
D03*
X142520Y-316535D02*
D03*
X302362Y-156693D02*
D03*
X142520Y-236614D02*
D03*
X258472Y-327165D02*
D03*
X302362Y-316535D02*
D03*
X246472Y-327165D02*
D03*
X258472D02*
D03*
X282283D02*
D03*
X294094D02*
D03*
X302362Y-156693D02*
D03*
Y-316535D02*
D03*
X142520D02*
D03*
Y-236614D02*
D03*
Y-156693D02*
D03*
X270472Y-327165D02*
D03*
X246472D02*
D03*
D242*
X470275Y-308597D02*
D03*
X391535D02*
D03*
X340904Y-273410D02*
D03*
Y-194670D02*
D03*
X391545Y-160477D02*
D03*
X470285D02*
D03*
X528395Y-194680D02*
D03*
Y-273420D02*
D03*
D243*
X285128Y-308632D02*
D03*
X160020Y-314535D02*
D03*
X162520Y-152693D02*
D03*
X284862Y-164793D02*
D03*
D244*
X604291Y-330039D02*
D03*
X574291D02*
D03*
D245*
X-18464Y-326781D02*
D03*
X1535D02*
D03*
Y-306781D02*
D03*
X-18464D02*
D03*
X-18465Y-273630D02*
D03*
X1535D02*
D03*
Y-253630D02*
D03*
X-18465D02*
D03*
Y-220480D02*
D03*
X1535D02*
D03*
Y-200480D02*
D03*
X-18465D02*
D03*
X-18464Y-167332D02*
D03*
X1535D02*
D03*
Y-147332D02*
D03*
X-18464D02*
D03*
D246*
X-8465Y-316781D02*
D03*
X-8465Y-263630D02*
D03*
Y-210480D02*
D03*
X-8465Y-157332D02*
D03*
D247*
X589055Y13937D02*
D03*
D248*
X579055D02*
D03*
X569055D02*
D03*
X559055D02*
D03*
X549055D02*
D03*
X539055D02*
D03*
X589055Y3937D02*
D03*
X579055D02*
D03*
X569055D02*
D03*
X559055D02*
D03*
X549055D02*
D03*
X539055D02*
D03*
D249*
X0Y0D02*
D03*
X0Y-378395D02*
D03*
X685039Y-340551D02*
D03*
X685039Y0D02*
D03*
X486221Y-340551D02*
D03*
D250*
X670538Y-74409D02*
D03*
X668438D02*
D03*
X676772Y-54331D02*
D03*
Y-51575D02*
D03*
X84079Y-105653D02*
D03*
X62986Y-112803D02*
D03*
X62499Y-117255D02*
D03*
X141981Y-347043D02*
D03*
X142520Y-342913D02*
D03*
X198392Y-366842D02*
D03*
X196701Y-370523D02*
D03*
X680709Y-216929D02*
D03*
X671654Y-217323D02*
D03*
X585433Y-114961D02*
D03*
X584252Y-117717D02*
D03*
X366929Y-75984D02*
D03*
Y-83071D02*
D03*
Y-86614D02*
D03*
Y-89370D02*
D03*
Y-79528D02*
D03*
X679921Y-160236D02*
D03*
X684646Y-161811D02*
D03*
X689370Y-161417D02*
D03*
X689764Y-164567D02*
D03*
Y-168110D02*
D03*
X625000Y-48080D02*
D03*
X476945Y-173228D02*
D03*
X555512Y-218504D02*
D03*
X381496Y-127165D02*
D03*
X378740Y-123622D02*
D03*
X377559Y-135433D02*
D03*
X381890Y-137402D02*
D03*
X377559Y-142126D02*
D03*
X381496Y-140945D02*
D03*
X474016Y-176378D02*
D03*
X460186Y-175448D02*
D03*
X578168Y-80778D02*
D03*
X530027Y-172987D02*
D03*
X533044Y-176225D02*
D03*
X495669Y-222047D02*
D03*
X500394Y-222835D02*
D03*
X157480Y-361811D02*
D03*
X153543Y-358661D02*
D03*
Y-361811D02*
D03*
X155512D02*
D03*
Y-358661D02*
D03*
X157480D02*
D03*
X644488Y-170472D02*
D03*
X644619Y-166285D02*
D03*
X644569Y-162910D02*
D03*
X644488Y-159843D02*
D03*
X435827Y-103543D02*
D03*
X402719Y-112334D02*
D03*
X409900Y-136559D02*
D03*
X430492Y-136473D02*
D03*
X414567Y-137402D02*
D03*
X436614Y-136614D02*
D03*
X443307Y-111024D02*
D03*
X664966Y-316582D02*
D03*
X664961Y-325984D02*
D03*
X692037Y-315878D02*
D03*
X692126Y-322441D02*
D03*
X256897Y-112001D02*
D03*
X255118Y-118504D02*
D03*
X254376Y-125747D02*
D03*
X241250Y-126247D02*
D03*
X238189Y-116142D02*
D03*
X246063Y-111024D02*
D03*
X248425Y-129134D02*
D03*
X241077Y-118805D02*
D03*
X255512Y-121260D02*
D03*
X253713Y-109190D02*
D03*
X253690Y-111960D02*
D03*
X267717Y-123622D02*
D03*
X271654Y-122835D02*
D03*
X267323Y-132677D02*
D03*
X272047Y-131496D02*
D03*
X244664Y-106952D02*
D03*
X228824Y-104850D02*
D03*
X577953Y-83858D02*
D03*
X618898Y-82284D02*
D03*
X612205Y-87008D02*
D03*
X609055Y-92520D02*
D03*
X620959Y-100047D02*
D03*
X612598Y-100000D02*
D03*
X629134Y-102756D02*
D03*
X631814Y-83784D02*
D03*
X629101Y-90137D02*
D03*
X623228Y-93307D02*
D03*
X616535Y-84646D02*
D03*
X616929Y-100000D02*
D03*
X599279Y-82981D02*
D03*
X597227Y-77103D02*
D03*
X601745Y-98051D02*
D03*
X588372Y-100945D02*
D03*
X567323Y-94095D02*
D03*
X569291Y-91339D02*
D03*
X568504Y-88189D02*
D03*
X579921Y-101969D02*
D03*
X584763Y-100116D02*
D03*
X588976Y-86221D02*
D03*
X600394Y-87795D02*
D03*
X592520Y-93307D02*
D03*
X666929Y-98032D02*
D03*
X662539Y-107066D02*
D03*
X667717Y-106693D02*
D03*
X696762Y-63288D02*
D03*
X696577Y-51453D02*
D03*
X675591Y-42520D02*
D03*
X685716Y-22157D02*
D03*
X679517Y-26553D02*
D03*
Y-37023D02*
D03*
X693915Y-33393D02*
D03*
X686728Y-33442D02*
D03*
X686319Y-43553D02*
D03*
X683127Y-66209D02*
D03*
X689466Y-66165D02*
D03*
X680082Y-64183D02*
D03*
X675926Y-72691D02*
D03*
X660719Y-75726D02*
D03*
X694095Y-62205D02*
D03*
X693977Y-53201D02*
D03*
X676378Y-83858D02*
D03*
X538583Y-111811D02*
D03*
X539233Y-115729D02*
D03*
X569092Y-108048D02*
D03*
X546386Y-109024D02*
D03*
X548093Y-185219D02*
D03*
X548425Y-181890D02*
D03*
X548819Y-178740D02*
D03*
X547244Y-157087D02*
D03*
Y-144488D02*
D03*
X524409Y-135827D02*
D03*
X531801Y-127495D02*
D03*
X539900Y-140766D02*
D03*
X570472Y-137795D02*
D03*
X579921Y-133465D02*
D03*
X574409D02*
D03*
X570866D02*
D03*
X572047Y-129921D02*
D03*
X576378D02*
D03*
X580315D02*
D03*
X646457Y-156693D02*
D03*
X642520D02*
D03*
X635039Y-216142D02*
D03*
X608661Y-236221D02*
D03*
X572441Y-227165D02*
D03*
X678441Y-292586D02*
D03*
X678346Y-297244D02*
D03*
X639764Y-283858D02*
D03*
X554724Y-294882D02*
D03*
X565354Y-292913D02*
D03*
X630577Y-278001D02*
D03*
X582874Y-294291D02*
D03*
X680709Y-212205D02*
D03*
X673622Y-213779D02*
D03*
X669685D02*
D03*
X666142Y-212992D02*
D03*
X599564Y-178940D02*
D03*
X594882Y-179134D02*
D03*
X589764D02*
D03*
X584646Y-178740D02*
D03*
X635827Y-187795D02*
D03*
X635433Y-184252D02*
D03*
X652756Y-164961D02*
D03*
X657480Y-164567D02*
D03*
X662992Y-164961D02*
D03*
X668504D02*
D03*
X681496Y-179528D02*
D03*
X677165Y-172441D02*
D03*
X673228D02*
D03*
X675197Y-200000D02*
D03*
X678740D02*
D03*
X681890D02*
D03*
Y-196850D02*
D03*
X678740D02*
D03*
X675591Y-196457D02*
D03*
X652756Y-218504D02*
D03*
X650000Y-231102D02*
D03*
X646434Y-231245D02*
D03*
X598425Y-198819D02*
D03*
X595276D02*
D03*
X592126D02*
D03*
X589764D02*
D03*
X587008D02*
D03*
X570079Y-200000D02*
D03*
X549298Y-191988D02*
D03*
X600000Y-248425D02*
D03*
X616535Y-255512D02*
D03*
X612205Y-251575D02*
D03*
X624803Y-255906D02*
D03*
Y-251575D02*
D03*
X624409Y-248031D02*
D03*
X611417Y-247638D02*
D03*
X605118Y-244488D02*
D03*
X673228Y-251181D02*
D03*
X672835Y-257087D02*
D03*
X673622Y-261417D02*
D03*
X676378Y-266142D02*
D03*
X676772Y-270866D02*
D03*
X671260Y-274803D02*
D03*
Y-278740D02*
D03*
X671654Y-283071D02*
D03*
X683858Y-310630D02*
D03*
X683716Y-298538D02*
D03*
X651575Y-275197D02*
D03*
X648819Y-278740D02*
D03*
X652362Y-279528D02*
D03*
X657087D02*
D03*
X654331Y-283858D02*
D03*
X650000D02*
D03*
X646457D02*
D03*
X637795Y-297638D02*
D03*
X585039Y-249606D02*
D03*
X590551Y-266535D02*
D03*
X588189Y-263386D02*
D03*
X585433Y-253937D02*
D03*
Y-257480D02*
D03*
X581496D02*
D03*
X577953D02*
D03*
X559842Y-257087D02*
D03*
X579134Y-195276D02*
D03*
X574803D02*
D03*
X577953Y-198819D02*
D03*
X590158Y-226378D02*
D03*
X586221Y-226772D02*
D03*
X579921Y-227559D02*
D03*
X576772Y-228740D02*
D03*
X637008Y-238583D02*
D03*
X608661Y-242126D02*
D03*
X590551Y-242520D02*
D03*
X586537Y-234843D02*
D03*
X546850Y-213779D02*
D03*
X548819Y-196063D02*
D03*
X547244Y-203150D02*
D03*
X554724Y-207874D02*
D03*
X549213D02*
D03*
X569291Y-194095D02*
D03*
X581496Y-198819D02*
D03*
X573622D02*
D03*
X571162Y-284136D02*
D03*
X577953Y-284646D02*
D03*
X574803Y-284252D02*
D03*
X568110D02*
D03*
X567717Y-259055D02*
D03*
X566535Y-255906D02*
D03*
X570079D02*
D03*
X548425Y-253543D02*
D03*
X545669Y-253937D02*
D03*
X545128Y-280872D02*
D03*
X544909Y-287437D02*
D03*
X545276Y-294094D02*
D03*
Y-275197D02*
D03*
Y-270866D02*
D03*
X544488Y-265748D02*
D03*
X557087Y-261417D02*
D03*
X556628Y-258042D02*
D03*
X569548Y-287223D02*
D03*
X595276Y-291732D02*
D03*
X612598D02*
D03*
X627559Y-296457D02*
D03*
X563386Y-257874D02*
D03*
X572441Y-258268D02*
D03*
X475984Y-127165D02*
D03*
X480120Y-132365D02*
D03*
X469685Y-133465D02*
D03*
X473228Y-105905D02*
D03*
X488583Y-132283D02*
D03*
X506299Y-129921D02*
D03*
X498032Y-132283D02*
D03*
X506207Y-127333D02*
D03*
X505905Y-123622D02*
D03*
X472441Y-113779D02*
D03*
X483484Y-105840D02*
D03*
X504703Y-106672D02*
D03*
X508268Y-117323D02*
D03*
X501669Y-116601D02*
D03*
X500313Y-105734D02*
D03*
X476772Y-123622D02*
D03*
X470472Y-123622D02*
D03*
X444507Y-309009D02*
D03*
X448819Y-309055D02*
D03*
X457480Y-306693D02*
D03*
X451575Y-309055D02*
D03*
X437048Y-308863D02*
D03*
X431102Y-308268D02*
D03*
X461811Y-327165D02*
D03*
X456693D02*
D03*
X454724D02*
D03*
X450394D02*
D03*
X448032D02*
D03*
X443701D02*
D03*
X441732D02*
D03*
X436614D02*
D03*
X429528Y-326772D02*
D03*
X434646Y-327559D02*
D03*
X518337Y-159634D02*
D03*
X515702Y-162803D02*
D03*
X498693Y-188351D02*
D03*
X498819Y-183858D02*
D03*
X499111Y-179528D02*
D03*
X658114Y-56714D02*
D03*
X657445Y-63525D02*
D03*
X658053Y-71188D02*
D03*
X623511Y-62552D02*
D03*
X623228Y-55118D02*
D03*
X623622Y-70866D02*
D03*
X43701Y-29921D02*
D03*
X55905Y-31496D02*
D03*
X111024Y-33071D02*
D03*
X125591Y-32283D02*
D03*
X64173Y-42520D02*
D03*
X101181Y-18504D02*
D03*
X101575Y-42126D02*
D03*
X670079Y-9449D02*
D03*
X673228Y-29528D02*
D03*
X671654Y-62598D02*
D03*
Y-41339D02*
D03*
X659449Y-49213D02*
D03*
X596063Y-53937D02*
D03*
X602756Y-39764D02*
D03*
X660236Y-14961D02*
D03*
X614567Y-44882D02*
D03*
X423461Y-178869D02*
D03*
X144871Y-131609D02*
D03*
X120079Y-263386D02*
D03*
X314417Y-228033D02*
D03*
X314623Y-231391D02*
D03*
X325984Y-272441D02*
D03*
X416835Y-196581D02*
D03*
X411811Y-196850D02*
D03*
X570866Y-70472D02*
D03*
Y-72441D02*
D03*
Y-74410D02*
D03*
X574016Y-70472D02*
D03*
Y-72441D02*
D03*
Y-74410D02*
D03*
X350787Y-116929D02*
D03*
X352756D02*
D03*
X354724D02*
D03*
X350787Y-113779D02*
D03*
X352756D02*
D03*
X354724D02*
D03*
X379134Y-137795D02*
D03*
X378740Y-127165D02*
D03*
X375532Y-123610D02*
D03*
X314658Y-244775D02*
D03*
X315097Y-235081D02*
D03*
X314503Y-225180D02*
D03*
X288583Y-225590D02*
D03*
X288189Y-228740D02*
D03*
Y-231102D02*
D03*
X288057Y-233478D02*
D03*
X288057Y-245095D02*
D03*
X288189Y-247638D02*
D03*
X287941Y-241819D02*
D03*
X288189Y-235827D02*
D03*
X588976Y-302756D02*
D03*
X579528Y-303150D02*
D03*
X615748Y-305512D02*
D03*
X562598Y-306693D02*
D03*
X377165Y-107283D02*
D03*
X383465Y-107480D02*
D03*
X375590Y-127165D02*
D03*
X106299Y-263632D02*
D03*
X380339Y-107321D02*
D03*
X154724Y-389616D02*
D03*
X156693D02*
D03*
X158661D02*
D03*
X154724Y-386466D02*
D03*
X156693D02*
D03*
X158661D02*
D03*
X531496Y-262647D02*
D03*
X461811Y-310679D02*
D03*
X450000Y-293750D02*
D03*
X422441Y-293789D02*
D03*
X531496Y-213435D02*
D03*
X338525Y-243567D02*
D03*
X525591Y-233088D02*
D03*
X439697Y-162549D02*
D03*
X343144Y-225173D02*
D03*
X420669Y-157923D02*
D03*
X531496Y-223277D02*
D03*
X338583Y-235236D02*
D03*
X525591Y-242962D02*
D03*
X430150Y-162253D02*
D03*
X343444Y-215373D02*
D03*
X432283Y-293750D02*
D03*
X410528Y-157923D02*
D03*
X342944Y-264473D02*
D03*
X444095Y-293750D02*
D03*
X422835Y-311072D02*
D03*
X531496Y-233088D02*
D03*
X430150Y-157923D02*
D03*
X338444Y-225173D02*
D03*
X402756Y-311072D02*
D03*
X525591Y-253969D02*
D03*
X420079Y-162549D02*
D03*
X343403Y-205651D02*
D03*
X525591Y-203592D02*
D03*
X400295Y-157824D02*
D03*
X343144Y-254773D02*
D03*
X431928Y-311189D02*
D03*
X531496Y-242962D02*
D03*
X338844Y-215273D02*
D03*
X402362Y-293750D02*
D03*
X525591Y-262647D02*
D03*
X410913Y-162758D02*
D03*
X338444Y-264473D02*
D03*
X456299Y-293750D02*
D03*
X437795Y-293750D02*
D03*
X525591Y-213435D02*
D03*
X459319Y-162510D02*
D03*
Y-157922D02*
D03*
X342744Y-243747D02*
D03*
X412598Y-311072D02*
D03*
X531496Y-253969D02*
D03*
X449803Y-157923D02*
D03*
X338744Y-205473D02*
D03*
X531496Y-203592D02*
D03*
X401279Y-162509D02*
D03*
X439961Y-157923D02*
D03*
X338444Y-254773D02*
D03*
X461417Y-293750D02*
D03*
X525591Y-223277D02*
D03*
X449508Y-162549D02*
D03*
X343504Y-235236D02*
D03*
X412205Y-293750D02*
D03*
X639750Y-314581D02*
D03*
X658647Y-314581D02*
D03*
X509405Y-345138D02*
D03*
X509011Y-330177D02*
D03*
X56441Y-143600D02*
D03*
Y-151600D02*
D03*
Y-191600D02*
D03*
Y-199600D02*
D03*
Y-215600D02*
D03*
Y-223600D02*
D03*
Y-231600D02*
D03*
Y-247600D02*
D03*
Y-255600D02*
D03*
Y-271600D02*
D03*
Y-279600D02*
D03*
Y-287600D02*
D03*
Y-303600D02*
D03*
Y-311600D02*
D03*
Y-327600D02*
D03*
Y-335600D02*
D03*
Y-343600D02*
D03*
Y-351600D02*
D03*
X54441Y-139600D02*
D03*
X52441Y-143600D02*
D03*
X54441Y-147600D02*
D03*
X52441Y-151600D02*
D03*
Y-191600D02*
D03*
X54441Y-195600D02*
D03*
X52441Y-199600D02*
D03*
X54441Y-203600D02*
D03*
X52441Y-215600D02*
D03*
X54441Y-219600D02*
D03*
X52441Y-223600D02*
D03*
X54441Y-227600D02*
D03*
X52441Y-231600D02*
D03*
X54441Y-235600D02*
D03*
Y-243600D02*
D03*
X52441Y-247600D02*
D03*
X54441Y-251600D02*
D03*
X52441Y-255600D02*
D03*
X54441Y-267600D02*
D03*
X52441Y-271600D02*
D03*
X54441Y-275600D02*
D03*
X52441Y-279600D02*
D03*
Y-287600D02*
D03*
X54441Y-291600D02*
D03*
Y-299600D02*
D03*
X52441Y-303600D02*
D03*
X54441Y-307600D02*
D03*
X52441Y-311600D02*
D03*
X54441Y-323600D02*
D03*
X52441Y-327600D02*
D03*
X54441Y-331600D02*
D03*
X52441Y-335600D02*
D03*
X54441Y-339600D02*
D03*
X52441Y-343600D02*
D03*
Y-351600D02*
D03*
X50441Y-139600D02*
D03*
X48441Y-143600D02*
D03*
X50441Y-195600D02*
D03*
X48441Y-199600D02*
D03*
Y-223600D02*
D03*
X50441Y-227600D02*
D03*
X48441Y-231600D02*
D03*
X50441Y-235600D02*
D03*
Y-243600D02*
D03*
X48441Y-247600D02*
D03*
X50441Y-251600D02*
D03*
Y-275600D02*
D03*
X48441Y-279600D02*
D03*
Y-287600D02*
D03*
X50441Y-291600D02*
D03*
Y-299600D02*
D03*
X48441Y-303600D02*
D03*
X50441Y-331600D02*
D03*
X48441Y-335600D02*
D03*
X50441Y-339600D02*
D03*
X48441Y-343600D02*
D03*
Y-351600D02*
D03*
X46441Y-139600D02*
D03*
X44441Y-143600D02*
D03*
X46441Y-227600D02*
D03*
X44441Y-231600D02*
D03*
X46441Y-235600D02*
D03*
Y-243600D02*
D03*
X44441Y-247600D02*
D03*
Y-279600D02*
D03*
Y-287600D02*
D03*
X46441Y-291600D02*
D03*
Y-299600D02*
D03*
Y-331600D02*
D03*
X44441Y-335600D02*
D03*
X46441Y-339600D02*
D03*
X44441Y-343600D02*
D03*
Y-351600D02*
D03*
X42441Y-139600D02*
D03*
X40441Y-143600D02*
D03*
Y-223600D02*
D03*
X42441Y-227600D02*
D03*
X40441Y-231600D02*
D03*
X42441Y-235600D02*
D03*
Y-243600D02*
D03*
X40441Y-247600D02*
D03*
X42441Y-299600D02*
D03*
Y-331600D02*
D03*
X40441Y-335600D02*
D03*
X42441Y-339600D02*
D03*
X40441Y-343600D02*
D03*
Y-351600D02*
D03*
X38441Y-139600D02*
D03*
X36441Y-143600D02*
D03*
Y-151600D02*
D03*
Y-215600D02*
D03*
Y-223600D02*
D03*
X38441Y-227600D02*
D03*
X36441Y-231600D02*
D03*
X38441Y-235600D02*
D03*
Y-243600D02*
D03*
X36441Y-247600D02*
D03*
X38441Y-251600D02*
D03*
X36441Y-255600D02*
D03*
Y-327600D02*
D03*
X38441Y-331600D02*
D03*
X36441Y-335600D02*
D03*
X38441Y-339600D02*
D03*
X36441Y-343600D02*
D03*
Y-351600D02*
D03*
X34441Y-139600D02*
D03*
X32441Y-143600D02*
D03*
X34441Y-147600D02*
D03*
X32441Y-151600D02*
D03*
X34441Y-163600D02*
D03*
Y-219600D02*
D03*
Y-227600D02*
D03*
Y-235600D02*
D03*
Y-243600D02*
D03*
Y-251600D02*
D03*
Y-267600D02*
D03*
Y-275600D02*
D03*
Y-299600D02*
D03*
Y-307600D02*
D03*
Y-323600D02*
D03*
X32441Y-327600D02*
D03*
X34441Y-331600D02*
D03*
X32441Y-335600D02*
D03*
X34441Y-339600D02*
D03*
X32441Y-343600D02*
D03*
Y-351600D02*
D03*
X30441Y-139600D02*
D03*
X28441Y-143600D02*
D03*
X30441Y-147600D02*
D03*
X28441Y-151600D02*
D03*
X30441Y-163600D02*
D03*
X28441Y-167600D02*
D03*
Y-327600D02*
D03*
X30441Y-331600D02*
D03*
X28441Y-335600D02*
D03*
X30441Y-339600D02*
D03*
X28441Y-343600D02*
D03*
Y-351600D02*
D03*
X26441Y-139600D02*
D03*
X24441Y-143600D02*
D03*
X26441Y-147600D02*
D03*
X24441Y-151600D02*
D03*
X26441Y-163600D02*
D03*
X24441Y-167600D02*
D03*
Y-191600D02*
D03*
X26441Y-195600D02*
D03*
X24441Y-287600D02*
D03*
X26441Y-299600D02*
D03*
X24441Y-303600D02*
D03*
X26441Y-307600D02*
D03*
X24441Y-311600D02*
D03*
X26441Y-331600D02*
D03*
X24441Y-335600D02*
D03*
X26441Y-339600D02*
D03*
X24441Y-343600D02*
D03*
Y-351600D02*
D03*
X22441Y-139600D02*
D03*
X20441Y-143600D02*
D03*
X22441Y-147600D02*
D03*
X20441Y-151600D02*
D03*
X22441Y-163600D02*
D03*
X20441Y-167600D02*
D03*
X22441Y-171600D02*
D03*
X20441Y-191600D02*
D03*
X22441Y-195600D02*
D03*
X20441Y-199600D02*
D03*
Y-231600D02*
D03*
X22441Y-235600D02*
D03*
Y-243600D02*
D03*
X20441Y-247600D02*
D03*
X22441Y-251600D02*
D03*
X20441Y-255600D02*
D03*
X22441Y-259600D02*
D03*
Y-267600D02*
D03*
X20441Y-271600D02*
D03*
X22441Y-283600D02*
D03*
X20441Y-287600D02*
D03*
X22441Y-291600D02*
D03*
Y-299600D02*
D03*
X20441Y-303600D02*
D03*
X22441Y-307600D02*
D03*
X20441Y-311600D02*
D03*
X22441Y-323600D02*
D03*
X20441Y-335600D02*
D03*
X22441Y-339600D02*
D03*
X20441Y-343600D02*
D03*
Y-351600D02*
D03*
X18441Y-139600D02*
D03*
X16441Y-143600D02*
D03*
X18441Y-147600D02*
D03*
X16441Y-151600D02*
D03*
X18441Y-163600D02*
D03*
X16441Y-167600D02*
D03*
X18441Y-171600D02*
D03*
X16441Y-191600D02*
D03*
X18441Y-195600D02*
D03*
X16441Y-199600D02*
D03*
X18441Y-203600D02*
D03*
X16441Y-215600D02*
D03*
X18441Y-219600D02*
D03*
X16441Y-223600D02*
D03*
X18441Y-235600D02*
D03*
Y-243600D02*
D03*
X16441Y-247600D02*
D03*
X18441Y-251600D02*
D03*
X16441Y-255600D02*
D03*
X18441Y-259600D02*
D03*
Y-267600D02*
D03*
X16441Y-271600D02*
D03*
X18441Y-275600D02*
D03*
X16441Y-279600D02*
D03*
X18441Y-291600D02*
D03*
Y-299600D02*
D03*
X16441Y-303600D02*
D03*
X18441Y-307600D02*
D03*
X16441Y-311600D02*
D03*
X18441Y-323600D02*
D03*
X16441Y-327600D02*
D03*
X18441Y-339600D02*
D03*
X16441Y-343600D02*
D03*
Y-351600D02*
D03*
X14441Y-139600D02*
D03*
X12441Y-143600D02*
D03*
X14441Y-147600D02*
D03*
X12441Y-151600D02*
D03*
X14441Y-163600D02*
D03*
X12441Y-167600D02*
D03*
X14441Y-171600D02*
D03*
X12441Y-191600D02*
D03*
X14441Y-195600D02*
D03*
X12441Y-199600D02*
D03*
X14441Y-203600D02*
D03*
X12441Y-215600D02*
D03*
X14441Y-219600D02*
D03*
X12441Y-223600D02*
D03*
X14441Y-243600D02*
D03*
X12441Y-247600D02*
D03*
X14441Y-251600D02*
D03*
X12441Y-255600D02*
D03*
X14441Y-259600D02*
D03*
Y-267600D02*
D03*
X12441Y-271600D02*
D03*
X14441Y-275600D02*
D03*
X12441Y-279600D02*
D03*
X14441Y-291600D02*
D03*
Y-299600D02*
D03*
X12441Y-303600D02*
D03*
X14441Y-307600D02*
D03*
X12441Y-311600D02*
D03*
X14441Y-323600D02*
D03*
X12441Y-327600D02*
D03*
X14441Y-331600D02*
D03*
X12441Y-343600D02*
D03*
Y-351600D02*
D03*
X10441Y-139600D02*
D03*
Y-163600D02*
D03*
Y-171600D02*
D03*
X8441Y-191600D02*
D03*
X10441Y-195600D02*
D03*
Y-203600D02*
D03*
Y-227600D02*
D03*
Y-243600D02*
D03*
X8441Y-247600D02*
D03*
X10441Y-251600D02*
D03*
Y-259600D02*
D03*
Y-267600D02*
D03*
Y-275600D02*
D03*
X8441Y-279600D02*
D03*
X10441Y-299600D02*
D03*
Y-323600D02*
D03*
Y-331600D02*
D03*
X8441Y-351600D02*
D03*
X6441Y-139600D02*
D03*
X4441Y-191600D02*
D03*
X6441Y-243600D02*
D03*
X4441Y-351600D02*
D03*
X2441Y-243600D02*
D03*
X441Y-351600D02*
D03*
X-3559Y-191600D02*
D03*
X-1559Y-243600D02*
D03*
X-3559Y-351600D02*
D03*
X-5559Y-139600D02*
D03*
X-7559Y-143600D02*
D03*
Y-167600D02*
D03*
Y-191600D02*
D03*
Y-199600D02*
D03*
Y-223600D02*
D03*
X-5559Y-227600D02*
D03*
Y-243600D02*
D03*
X-7559Y-247600D02*
D03*
Y-279600D02*
D03*
X-5559Y-299600D02*
D03*
X-7559Y-303600D02*
D03*
Y-327600D02*
D03*
Y-351600D02*
D03*
X-9559Y-139600D02*
D03*
Y-171600D02*
D03*
X-11559Y-191600D02*
D03*
X-9559Y-195600D02*
D03*
Y-227600D02*
D03*
Y-243600D02*
D03*
X-11559Y-247600D02*
D03*
X-9559Y-251600D02*
D03*
Y-275600D02*
D03*
X-11559Y-279600D02*
D03*
X-9559Y-299600D02*
D03*
Y-331600D02*
D03*
X-11559Y-351600D02*
D03*
X-13559Y-139600D02*
D03*
X-15559Y-191600D02*
D03*
X-13559Y-243600D02*
D03*
X-15559Y-351600D02*
D03*
X-19559Y-263600D02*
D03*
Y-351600D02*
D03*
X-23559Y-159600D02*
D03*
Y-191600D02*
D03*
X-21559Y-211600D02*
D03*
X-23559Y-263600D02*
D03*
X-21559Y-315600D02*
D03*
X-23559Y-351600D02*
D03*
X-25559Y-139600D02*
D03*
Y-155600D02*
D03*
Y-211600D02*
D03*
Y-259600D02*
D03*
Y-267600D02*
D03*
Y-299600D02*
D03*
Y-315600D02*
D03*
X234252Y-133742D02*
D03*
X263779Y-106151D02*
D03*
X71850Y-147638D02*
D03*
X75787Y-131890D02*
D03*
X623000Y-37402D02*
D03*
X610236Y-8858D02*
D03*
X609252Y-26575D02*
D03*
X98425Y-102362D02*
D03*
X89567D02*
D03*
X85630Y-313976D02*
D03*
X86614Y-258858D02*
D03*
X81693Y-205709D02*
D03*
X360236Y-268586D02*
D03*
Y-272490D02*
D03*
X63976Y-227362D02*
D03*
X68898Y-285433D02*
D03*
X67913Y-340551D02*
D03*
X68573Y-179321D02*
D03*
X44291Y-252953D02*
D03*
Y-272638D02*
D03*
Y-326772D02*
D03*
Y-307087D02*
D03*
X26575Y-291339D02*
D03*
X31496Y-189961D02*
D03*
X44291Y-147638D02*
D03*
Y-167323D02*
D03*
Y-200787D02*
D03*
Y-220472D02*
D03*
X325787Y-243205D02*
D03*
Y-233362D02*
D03*
X103409Y-141732D02*
D03*
X103347Y-110236D02*
D03*
X119095Y-126047D02*
D03*
X518701Y-104214D02*
D03*
X519587Y-134596D02*
D03*
X528543Y-104214D02*
D03*
X658465Y-21899D02*
D03*
X625000Y-29773D02*
D03*
X114173Y-83088D02*
D03*
X441929Y-122883D02*
D03*
X129921Y-79576D02*
D03*
X163071Y-390730D02*
D03*
X99410Y-50049D02*
D03*
X26495Y-8991D02*
D03*
X512657Y-270462D02*
D03*
X259285Y-390247D02*
D03*
X267204Y-390009D02*
D03*
X216162Y-390947D02*
D03*
X235144Y-390416D02*
D03*
X251456Y-390009D02*
D03*
X226063Y-390722D02*
D03*
X281201Y-390009D02*
D03*
X174941Y-390600D02*
D03*
X202441D02*
D03*
X544291Y-199655D02*
D03*
X509842Y-197687D02*
D03*
X544291Y-201624D02*
D03*
X509842Y-199655D02*
D03*
Y-201624D02*
D03*
X544291Y-197687D02*
D03*
X509842Y-195718D02*
D03*
X361811Y-207087D02*
D03*
X361417Y-203150D02*
D03*
X326969Y-197573D02*
D03*
X326966Y-195171D02*
D03*
X366535Y-202362D02*
D03*
X358661Y-194488D02*
D03*
X634252Y-314567D02*
D03*
X653150Y-314567D02*
D03*
X509391Y-350636D02*
D03*
X508997Y-335675D02*
D03*
X447244Y-324852D02*
D03*
X451181D02*
D03*
X433858D02*
D03*
X460630D02*
D03*
X437795D02*
D03*
X431102D02*
D03*
X444488D02*
D03*
X457480D02*
D03*
X453937D02*
D03*
X440551D02*
D03*
X222638Y-374655D02*
D03*
X218445Y-374108D02*
D03*
X453937Y-306742D02*
D03*
X451181D02*
D03*
X109409Y-140111D02*
D03*
X105409D02*
D03*
X101409D02*
D03*
X97409D02*
D03*
X65945Y-57923D02*
D03*
X615158Y-8858D02*
D03*
X70866Y-122047D02*
D03*
X360204Y-252984D02*
D03*
X417596Y-175197D02*
D03*
X377921Y-203740D02*
D03*
X372016Y-200787D02*
D03*
X354541Y-223636D02*
D03*
X354452Y-235236D02*
D03*
X356578Y-225247D02*
D03*
X379921Y-201740D02*
D03*
X102528Y-211583D02*
D03*
X97125Y-219488D02*
D03*
X99410Y-216535D02*
D03*
X101378Y-214567D02*
D03*
X86614Y-175197D02*
D03*
X361652Y-235205D02*
D03*
X359131Y-223425D02*
D03*
X361531D02*
D03*
X360236Y-262186D02*
D03*
Y-266186D02*
D03*
X85416Y-317699D02*
D03*
X85630Y-263779D02*
D03*
X86562Y-211183D02*
D03*
X411043Y-174974D02*
D03*
X413440Y-174850D02*
D03*
X421596Y-175034D02*
D03*
X406528Y-157767D02*
D03*
X404528Y-163386D02*
D03*
X407480Y-160433D02*
D03*
X86614Y-221457D02*
D03*
X427165Y-175246D02*
D03*
X75787Y-232283D02*
D03*
X87167Y-166377D02*
D03*
X89567Y-166370D02*
D03*
X85630Y-213583D02*
D03*
Y-266179D02*
D03*
Y-320313D02*
D03*
X543276Y-226591D02*
D03*
X544294Y-224248D02*
D03*
X544291Y-233268D02*
D03*
X359252Y-235236D02*
D03*
X356852D02*
D03*
X407480Y-163386D02*
D03*
X47244Y-8858D02*
D03*
X40354D02*
D03*
X33465D02*
D03*
X26575Y19685D02*
D03*
X86614Y-227362D02*
D03*
X63976Y-221457D02*
D03*
X82677Y-232283D02*
D03*
X63976Y-275590D02*
D03*
X75787Y-285433D02*
D03*
X87598Y-275590D02*
D03*
Y-281496D02*
D03*
X81880Y-287582D02*
D03*
X62992Y-329724D02*
D03*
X74803Y-339567D02*
D03*
X78740Y-340551D02*
D03*
X87598Y-335630D02*
D03*
Y-329724D02*
D03*
X63976Y-179134D02*
D03*
X74803D02*
D03*
X86562Y-169257D02*
D03*
X80709Y-180118D02*
D03*
X26575Y-283465D02*
D03*
X30512Y-170276D02*
D03*
X323850Y-241173D02*
D03*
Y-237205D02*
D03*
X323819Y-231299D02*
D03*
X325787Y-229362D02*
D03*
X323819Y-227362D02*
D03*
X325787Y-239205D02*
D03*
X-23622Y-342520D02*
D03*
X89567Y-140270D02*
D03*
X87254Y-139629D02*
D03*
X119095Y-130047D02*
D03*
X117126Y-132047D02*
D03*
X107346Y-110236D02*
D03*
X105347Y-112205D02*
D03*
X99347Y-110236D02*
D03*
X109409Y-112236D02*
D03*
X119095Y-122047D02*
D03*
X-23622Y-229331D02*
D03*
Y-233268D02*
D03*
Y-237205D02*
D03*
Y-241142D02*
D03*
Y-282480D02*
D03*
Y-286417D02*
D03*
Y-290354D02*
D03*
Y-294291D02*
D03*
Y-335630D02*
D03*
Y-339567D02*
D03*
Y-346457D02*
D03*
X107409Y-141732D02*
D03*
X99410D02*
D03*
X-23622Y-70866D02*
D03*
Y-66929D02*
D03*
Y-62992D02*
D03*
Y-60039D02*
D03*
Y-102362D02*
D03*
Y-106299D02*
D03*
Y-110236D02*
D03*
Y-114173D02*
D03*
Y-187992D02*
D03*
Y-184055D02*
D03*
Y-181102D02*
D03*
Y-177165D02*
D03*
X117126Y-128047D02*
D03*
Y-124047D02*
D03*
Y-119921D02*
D03*
X101284Y-112205D02*
D03*
X97284D02*
D03*
X544291Y-195718D02*
D03*
X469521Y-137615D02*
D03*
X533878Y-117716D02*
D03*
X524606Y-125836D02*
D03*
X524557Y-128740D02*
D03*
X450850Y-174127D02*
D03*
X512795Y-104214D02*
D03*
X463551Y-116025D02*
D03*
X658465Y-37647D02*
D03*
Y-29773D02*
D03*
X625000Y-21899D02*
D03*
X190354Y-377411D02*
D03*
X314961Y-118947D02*
D03*
X430807Y-175344D02*
D03*
X309016Y-128659D02*
D03*
X418898Y-144143D02*
D03*
X416106Y-144180D02*
D03*
X398568Y-145083D02*
D03*
X210433Y-374655D02*
D03*
X206496D02*
D03*
X442126Y-306742D02*
D03*
X439370D02*
D03*
X237992Y-374655D02*
D03*
X241929D02*
D03*
X253655Y-374421D02*
D03*
X256890Y-374655D02*
D03*
X273425D02*
D03*
X269502Y-374291D02*
D03*
X246339Y-386975D02*
D03*
X249410Y-387253D02*
D03*
X232480D02*
D03*
X229331D02*
D03*
X436221Y-306742D02*
D03*
X212795Y-387253D02*
D03*
X433465Y-306742D02*
D03*
X215945Y-387253D02*
D03*
X262006Y-387255D02*
D03*
X448032Y-306742D02*
D03*
X265158Y-387253D02*
D03*
X445276Y-306742D02*
D03*
X104528Y-92175D02*
D03*
X269685Y-106151D02*
D03*
X131890Y-72687D02*
D03*
X179134Y-386466D02*
D03*
Y-389616D02*
D03*
X178543Y-377411D02*
D03*
X443898Y-175049D02*
D03*
X99410Y-65797D02*
D03*
Y-57923D02*
D03*
X65945Y-65797D02*
D03*
Y-50049D02*
D03*
X78740Y-238041D02*
D03*
X33465Y19833D02*
D03*
X40354Y19685D02*
D03*
X47244D02*
D03*
X456742Y-116043D02*
D03*
X464328Y-146397D02*
D03*
X469291Y-143848D02*
D03*
X461319Y-143750D02*
D03*
X457283Y-175147D02*
D03*
X469390D02*
D03*
X544291Y-215403D02*
D03*
X512402Y-261958D02*
D03*
Y-265108D02*
D03*
X512543Y-268065D02*
D03*
X437697Y-175246D02*
D03*
X433858D02*
D03*
X404823Y-175344D02*
D03*
X402264D02*
D03*
X309016Y-113986D02*
D03*
X193898Y-115009D02*
D03*
Y-119931D02*
D03*
X309055Y-123868D02*
D03*
X182677Y-386466D02*
D03*
X186614D02*
D03*
X182677Y-389616D02*
D03*
X186614D02*
D03*
D251*
X348211Y-89891D02*
D03*
X357798Y-89963D02*
D03*
D252*
X651545Y-95108D02*
D03*
X413356Y7254D02*
D03*
Y-95108D02*
D03*
X651545Y7254D02*
D03*
X71880Y7412D02*
D03*
X310069Y-94950D02*
D03*
Y7412D02*
D03*
X71880Y-94950D02*
D03*
D253*
X99016Y-121653D02*
D03*
X103347D02*
D03*
X107677D02*
D03*
X99016Y-125984D02*
D03*
X103347D02*
D03*
X107677D02*
D03*
X99016Y-130315D02*
D03*
X103347D02*
D03*
X107677D02*
D03*
D254*
X218189Y-404100D02*
D03*
D255*
X644488Y-201575D02*
Y-170472D01*
Y-201575D02*
X664173Y-221260D01*
Y-294488D02*
Y-221260D01*
X646457Y-312205D02*
X664173Y-294488D01*
X644488Y-159843D02*
Y-157480D01*
Y-170472D02*
Y-159843D01*
X154921Y-360433D02*
X167323Y-348031D01*
X344094D01*
X646457Y-324803D02*
Y-312205D01*
X630315Y-340945D02*
X646457Y-324803D01*
X536614Y-340945D02*
X630315D01*
X471654Y-275984D02*
X536614Y-340945D01*
X398819Y-275984D02*
X471654D01*
X370866Y-303937D02*
X398819Y-275984D01*
X370866Y-321260D02*
Y-303937D01*
X344094Y-348031D02*
X370866Y-321260D01*
D256*
X156644Y-388287D02*
D03*
X184518Y-388354D02*
D03*
M02*
